FILE_TYPE = MACRO_DRAWING;
SET COLOR_WIRE YELLOW;
SET COLOR_PROP ORANGE;
SET COLOR_DOT WHITE;
SET COLOR_ARC YELLOW;
SET COLOR_BODY GREEN;
SET COLOR_NOTE PURPLE;
SET PROP_DISPLAY VALUE;
SET PAGE_NUMBER P163;
FORCEADD UNIVERSAL_GND..1
(-2700 -2250);
FORCEPROP 3 LASTPIN (-2700 -2200) SIG_NAME AGND_HSC\g
J 0
(-2690 -2190);
DISPLAY 0.659574 (-2690 -2190);
PAINT MONO (-2690 -2190);
DISPLAY INVISIBLE (-2690 -2190);
FORCEPROP 1 LAST HDL_POWER AGND_HSC
J 1
(-2675 -2325);
DISPLAY 0.723404 (-2675 -2325);
PAINT GREEN (-2675 -2325);
FORCEPROP 2 LAST CDS_LIB pure_quanta_power
J 0
(-2700 -2250);
DISPLAY INVISIBLE (-2700 -2250);
FORCEPROP 1 LAST PATH I1
J 0
(-2625 -2250);
DISPLAY 0.872340 (-2625 -2250);
PAINT AQUA (-2625 -2250);
DISPLAY INVISIBLE (-2625 -2250);
FORCEADD OFFPAGE..4
R 2
(-2025 -1300);
FORCEPROP 2 LAST $XR2 303 
J 0
(-2517 -1300);
DISPLAY 0.638298 (-2517 -1300);
PAINT MONO (-2517 -1300);
FORCEPROP 2 LAST $XR1 302 
J 0
(-2397 -1300);
DISPLAY 0.638298 (-2397 -1300);
PAINT MONO (-2397 -1300);
FORCEPROP 2 LAST $XR0 301 
J 0
(-2277 -1300);
DISPLAY 0.638298 (-2277 -1300);
PAINT MONO (-2277 -1300);
FORCEPROP 2 LAST CDS_LIB standard
J 0
(-2025 -1300);
DISPLAY INVISIBLE (-2025 -1300);
FORCEPROP 1 LAST OFFPAGE TRUE
J 2
(-2350 -1425);
DISPLAY 0.872340 (-2350 -1425);
PAINT GREEN (-2350 -1425);
DISPLAY INVISIBLE (-2350 -1425);
FORCEPROP 1 LAST COMMENT_BODY TRUE
J 2
(-2000 -1400);
DISPLAY 0.872340 (-2000 -1400);
PAINT GREEN (-2000 -1400);
DISPLAY INVISIBLE (-2000 -1400);
FORCEPROP 2 LAST PATH I10
J 0
(-2275 -1250);
DISPLAY 1.021277 (-2275 -1250);
DISPLAY INVISIBLE (-2275 -1250);
FORCEADD Q_RES..1
(-1900 -1125);
FORCEPROP 1 LAST LOCATION PR3984
J 0
(-2200 -1125);
DISPLAY 0.723404 (-2200 -1125);
PAINT AQUA (-2200 -1125);
FORCEPROP 0 LAST $SEC 1
J 0
(-1850 -1050);
DISPLAY 0.680851 (-1850 -1050);
PAINT MONO (-1850 -1050);
DISPLAY INVISIBLE (-1850 -1050);
FORCEPROP 0 LAST CDS_SEC 1
J 0
(-1850 -1050);
DISPLAY 1.021277 (-1850 -1050);
DISPLAY INVISIBLE (-1850 -1050);
FORCEPROP 1 LASTPIN (-2000 -1125) $PN 1
J 0
(-1988 -1113);
DISPLAY 0.787234 (-1988 -1113);
PAINT MONO (-1988 -1113);
FORCEPROP 1 LASTPIN (-1800 -1125) $PN 2
J 0
(-1838 -1113);
DISPLAY 0.787234 (-1838 -1113);
PAINT MONO (-1838 -1113);
FORCEPROP 1 LAST MATERIAL CHIP
J 0
(-1850 -1250);
DISPLAY 0.723404 (-1850 -1250);
PAINT SKYBLUE (-1850 -1250);
FORCEPROP 1 LAST VALUE 120K
J 2
(-1925 -1200);
DISPLAY 0.723404 (-1925 -1200);
PAINT SKYBLUE (-1925 -1200);
FORCEPROP 1 LAST TOLERANCE 1%
J 0
(-1875 -1200);
DISPLAY 0.723404 (-1875 -1200);
PAINT SKYBLUE (-1875 -1200);
FORCEPROP 1 LAST WATTAGE 1/16W
J 2
(-1875 -1250);
DISPLAY 0.723404 (-1875 -1250);
PAINT SKYBLUE (-1875 -1250);
FORCEPROP 1 LAST PACK_TYPE 0402LF
J 0
(-1775 -1200);
DISPLAY 0.723404 (-1775 -1200);
PAINT SKYBLUE (-1775 -1200);
FORCEPROP 1 LAST PART_NUMBER CS41202FB05
J 0
(-1775 -1125);
DISPLAY 0.723404 (-1775 -1125);
PAINT WHITE (-1775 -1125);
FORCEPROP 2 LAST CDS_LIB pure_quanta
J 0
(-1900 -1125);
DISPLAY INVISIBLE (-1900 -1125);
FORCEPROP 1 LAST PATH I11
J 0
(-1950 -975);
DISPLAY 0.978723 (-1950 -975);
PAINT WHITE (-1950 -975);
DISPLAY INVISIBLE (-1950 -975);
FORCEADD Q_CAP..1
(-1975 -1950);
FORCEPROP 1 LAST LOCATION PC2349
J 0
(-1900 -1850);
DISPLAY 0.808511 (-1900 -1850);
PAINT AQUA (-1900 -1850);
FORCEPROP 0 LAST $SEC 1
J 0
(-1900 -1800);
DISPLAY 0.680851 (-1900 -1800);
PAINT MONO (-1900 -1800);
DISPLAY INVISIBLE (-1900 -1800);
FORCEPROP 0 LAST CDS_SEC 1
J 0
(-1900 -1800);
DISPLAY 1.021277 (-1900 -1800);
DISPLAY INVISIBLE (-1900 -1800);
FORCEPROP 1 LASTPIN (-1975 -1850) $PN 1
J 0
(-1965 -1870);
DISPLAY 0.787234 (-1965 -1870);
PAINT MONO (-1965 -1870);
FORCEPROP 1 LASTPIN (-1975 -2050) $PN 2
J 0
(-1965 -2070);
DISPLAY 0.787234 (-1965 -2070);
PAINT MONO (-1965 -2070);
FORCEPROP 1 LAST PART_NUMBER CH21006KB16
J 0
(-1900 -2050);
DISPLAY 0.723404 (-1900 -2050);
PAINT WHITE (-1900 -2050);
FORCEPROP 1 LAST PACK_TYPE 0402
J 0
(-1900 -2100);
DISPLAY 0.723404 (-1900 -2100);
PAINT SKYBLUE (-1900 -2100);
FORCEPROP 1 LAST MATERIAL EMPTY
J 0
(-1900 -2000);
DISPLAY 0.723404 (-1900 -2000);
PAINT RED (-1900 -2000);
FORCEPROP 1 LAST VOLTAGE 50V
J 0
(-1900 -1950);
DISPLAY 0.723404 (-1900 -1950);
PAINT SKYBLUE (-1900 -1950);
FORCEPROP 1 LAST VALUE 1NF
J 0
(-1900 -1900);
DISPLAY 0.723404 (-1900 -1900);
PAINT SKYBLUE (-1900 -1900);
FORCEPROP 2 LAST CDS_LIB pure_quanta
J 0
(-1975 -1950);
DISPLAY INVISIBLE (-1975 -1950);
FORCEPROP 1 LAST TOLERANCE 10%
J 0
(-1925 -2000);
DISPLAY 0.978723 (-1925 -2000);
PAINT SKYBLUE (-1925 -2000);
DISPLAY INVISIBLE (-1925 -2000);
FORCEPROP 1 LAST PATH I12
J 0
(-1925 -1800);
DISPLAY 0.978723 (-1925 -1800);
PAINT WHITE (-1925 -1800);
DISPLAY INVISIBLE (-1925 -1800);
FORCEADD Q_RES..2
(-1475 -1950);
FORCEPROP 1 LAST LOCATION PR3987
J 0
(-1420 -1800);
DISPLAY 0.723404 (-1420 -1800);
PAINT AQUA (-1420 -1800);
FORCEPROP 0 LAST $SEC 1
J 0
(-1400 -1750);
DISPLAY 0.680851 (-1400 -1750);
PAINT MONO (-1400 -1750);
DISPLAY INVISIBLE (-1400 -1750);
FORCEPROP 0 LAST CDS_SEC 1
J 0
(-1400 -1750);
DISPLAY 1.021277 (-1400 -1750);
DISPLAY INVISIBLE (-1400 -1750);
FORCEPROP 1 LASTPIN (-1475 -1850) $PN 1
J 0
(-1470 -1888);
DISPLAY 0.787234 (-1470 -1888);
PAINT MONO (-1470 -1888);
FORCEPROP 1 LASTPIN (-1475 -2050) $PN 2
J 0
(-1470 -2040);
DISPLAY 0.787234 (-1470 -2040);
PAINT MONO (-1470 -2040);
FORCEPROP 1 LAST WATTAGE 1/16W
J 0
(-1425 -1950);
DISPLAY 0.723404 (-1425 -1950);
PAINT SKYBLUE (-1425 -1950);
FORCEPROP 1 LAST TOLERANCE 0.1%
J 0
(-1420 -1900);
DISPLAY 0.723404 (-1420 -1900);
PAINT SKYBLUE (-1420 -1900);
FORCEPROP 1 LAST MATERIAL CHIP
J 0
(-1425 -2000);
DISPLAY 0.723404 (-1425 -2000);
PAINT SKYBLUE (-1425 -2000);
FORCEPROP 1 LAST PART_NUMBER CS22002BB07
J 0
(-1425 -2050);
DISPLAY 0.723404 (-1425 -2050);
PAINT WHITE (-1425 -2050);
FORCEPROP 1 LAST PACK_TYPE 0402LF
J 0
(-1425 -2100);
DISPLAY 0.723404 (-1425 -2100);
PAINT SKYBLUE (-1425 -2100);
FORCEPROP 1 LAST VALUE 2K
J 0
(-1420 -1850);
DISPLAY 0.723404 (-1420 -1850);
PAINT SKYBLUE (-1420 -1850);
FORCEPROP 2 LAST CDS_LIB pure_quanta
J 0
(-1475 -1950);
DISPLAY INVISIBLE (-1475 -1950);
FORCEPROP 1 LAST PATH I13
J 0
(-1425 -1775);
DISPLAY 0.978723 (-1425 -1775);
PAINT WHITE (-1425 -1775);
DISPLAY INVISIBLE (-1425 -1775);
FORCEADD Q_RES..2
(-950 -1950);
FORCEPROP 1 LAST LOCATION PR3991
J 0
(-895 -1800);
DISPLAY 0.723404 (-895 -1800);
PAINT AQUA (-895 -1800);
FORCEPROP 0 LAST $SEC 1
J 0
(-875 -1750);
DISPLAY 0.680851 (-875 -1750);
PAINT MONO (-875 -1750);
DISPLAY INVISIBLE (-875 -1750);
FORCEPROP 0 LAST CDS_SEC 1
J 0
(-875 -1750);
DISPLAY 1.021277 (-875 -1750);
DISPLAY INVISIBLE (-875 -1750);
FORCEPROP 1 LASTPIN (-950 -1850) $PN 1
J 0
(-945 -1888);
DISPLAY 0.787234 (-945 -1888);
PAINT MONO (-945 -1888);
FORCEPROP 1 LASTPIN (-950 -2050) $PN 2
J 0
(-945 -2040);
DISPLAY 0.787234 (-945 -2040);
PAINT MONO (-945 -2040);
FORCEPROP 1 LAST WATTAGE 1/16W
J 0
(-900 -1950);
DISPLAY 0.723404 (-900 -1950);
PAINT SKYBLUE (-900 -1950);
FORCEPROP 1 LAST MATERIAL CHIP
J 0
(-900 -2000);
DISPLAY 0.723404 (-900 -2000);
PAINT SKYBLUE (-900 -2000);
FORCEPROP 1 LAST PART_NUMBER CS22002BB07
J 0
(-900 -2050);
DISPLAY 0.723404 (-900 -2050);
PAINT WHITE (-900 -2050);
FORCEPROP 1 LAST PACK_TYPE 0402LF
J 0
(-900 -2100);
DISPLAY 0.723404 (-900 -2100);
PAINT SKYBLUE (-900 -2100);
FORCEPROP 1 LAST VALUE 2K
J 0
(-895 -1850);
DISPLAY 0.723404 (-895 -1850);
PAINT SKYBLUE (-895 -1850);
FORCEPROP 1 LAST TOLERANCE 0.1%
J 0
(-895 -1900);
DISPLAY 0.723404 (-895 -1900);
PAINT SKYBLUE (-895 -1900);
FORCEPROP 2 LAST CDS_LIB pure_quanta
J 0
(-950 -1950);
DISPLAY INVISIBLE (-950 -1950);
FORCEPROP 1 LAST PATH I14
J 0
(-900 -1775);
DISPLAY 0.978723 (-900 -1775);
PAINT WHITE (-900 -1775);
DISPLAY INVISIBLE (-900 -1775);
FORCEADD OFFPAGE..5
(-1050 -1725);
FORCEPROP 2 LAST $XR2 301 
J 0
(-1305 -1761);
DISPLAY 0.638298 (-1305 -1761);
PAINT MONO (-1305 -1761);
FORCEPROP 2 LAST $XR1 303 
J 0
(-1425 -1725);
DISPLAY 0.638298 (-1425 -1725);
PAINT MONO (-1425 -1725);
FORCEPROP 2 LAST $XR0 302 
J 0
(-1305 -1725);
DISPLAY 0.638298 (-1305 -1725);
PAINT MONO (-1305 -1725);
FORCEPROP 2 LAST CDS_LIB standard
J 0
(-1050 -1725);
DISPLAY INVISIBLE (-1050 -1725);
FORCEPROP 1 LAST OFFPAGE TRUE
J 0
(-725 -1850);
DISPLAY 0.872340 (-725 -1850);
PAINT AQUA (-725 -1850);
DISPLAY INVISIBLE (-725 -1850);
FORCEPROP 1 LAST COMMENT_BODY TRUE
J 0
(-950 -1800);
DISPLAY 1.170213 (-950 -1800);
PAINT GREEN (-950 -1800);
DISPLAY INVISIBLE (-950 -1800);
FORCEPROP 2 LAST PATH I15
J 0
(-1300 -1675);
DISPLAY 1.021277 (-1300 -1675);
DISPLAY INVISIBLE (-1300 -1675);
FORCEADD Q_RES..1
(-1300 -1300);
FORCEPROP 1 LAST LOCATION PR3989
J 0
(-1600 -1300);
DISPLAY 0.723404 (-1600 -1300);
PAINT AQUA (-1600 -1300);
FORCEPROP 0 LAST $SEC 1
J 0
(-1175 -1225);
DISPLAY 0.680851 (-1175 -1225);
PAINT MONO (-1175 -1225);
DISPLAY INVISIBLE (-1175 -1225);
FORCEPROP 0 LAST CDS_SEC 1
J 0
(-1175 -1225);
DISPLAY 1.021277 (-1175 -1225);
DISPLAY INVISIBLE (-1175 -1225);
FORCEPROP 1 LASTPIN (-1400 -1300) $PN 1
J 0
(-1388 -1288);
DISPLAY 0.787234 (-1388 -1288);
PAINT MONO (-1388 -1288);
FORCEPROP 1 LASTPIN (-1200 -1300) $PN 2
J 0
(-1238 -1288);
DISPLAY 0.787234 (-1238 -1288);
PAINT MONO (-1238 -1288);
FORCEPROP 1 LAST WATTAGE 1/16W
J 2
(-1425 -1400);
DISPLAY 0.723404 (-1425 -1400);
PAINT SKYBLUE (-1425 -1400);
FORCEPROP 1 LAST PART_NUMBER CS00002JB13
J 0
(-1625 -1350);
DISPLAY 0.723404 (-1625 -1350);
PAINT WHITE (-1625 -1350);
FORCEPROP 1 LAST MATERIAL CHIP
J 0
(-1150 -1400);
DISPLAY 0.723404 (-1150 -1400);
PAINT SKYBLUE (-1150 -1400);
FORCEPROP 1 LAST TOLERANCE 5%
J 0
(-1175 -1350);
DISPLAY 0.723404 (-1175 -1350);
PAINT SKYBLUE (-1175 -1350);
FORCEPROP 1 LAST PACK_TYPE 0402LF
J 0
(-1375 -1400);
DISPLAY 0.723404 (-1375 -1400);
PAINT SKYBLUE (-1375 -1400);
FORCEPROP 1 LAST VALUE 0
J 2
(-1125 -1275);
DISPLAY 0.723404 (-1125 -1275);
PAINT SKYBLUE (-1125 -1275);
FORCEPROP 2 LAST CDS_LIB pure_quanta
J 0
(-1300 -1300);
DISPLAY INVISIBLE (-1300 -1300);
FORCEPROP 1 LAST PATH I16
J 0
(-1350 -1150);
DISPLAY 0.978723 (-1350 -1150);
PAINT WHITE (-1350 -1150);
DISPLAY INVISIBLE (-1350 -1150);
FORCEADD MP5991GLUZ..1
(25 -1200);
FORCEPROP 1 LAST LOCATION PU297
J 0
(-300 -200);
DISPLAY 1.148936 (-300 -200);
PAINT GREEN (-300 -200);
FORCEPROP 2 LAST SEC 1
J 0
(-275 25);
DISPLAY 0.680851 (-275 25);
PAINT MONO (-275 25);
DISPLAY INVISIBLE (-275 25);
FORCEPROP 2 LASTPIN (-450 -1625) $PN 23
J 2
(-460 -1615);
DISPLAY 0.680851 (-460 -1615);
PAINT MONO (-460 -1615);
FORCEPROP 2 LASTPIN (500 -1275) $PN 3
J 0
(510 -1265);
DISPLAY 0.680851 (510 -1265);
PAINT MONO (510 -1265);
FORCEPROP 2 LASTPIN (500 -1375) $PN 6
J 0
(510 -1365);
DISPLAY 0.680851 (510 -1365);
PAINT MONO (510 -1365);
FORCEPROP 2 LASTPIN (-450 -1925) $PN 20
J 2
(-460 -1915);
DISPLAY 0.680851 (-460 -1915);
PAINT MONO (-460 -1915);
FORCEPROP 2 LASTPIN (500 -1575) $PN 5
J 0
(510 -1565);
DISPLAY 0.680851 (510 -1565);
PAINT MONO (510 -1565);
FORCEPROP 2 LASTPIN (-450 -1725) $PN 22
J 2
(-460 -1715);
DISPLAY 0.680851 (-460 -1715);
PAINT MONO (-460 -1715);
FORCEPROP 2 LASTPIN (-450 -1125) $PN 8
J 2
(-460 -1115);
DISPLAY 0.680851 (-460 -1115);
PAINT MONO (-460 -1115);
FORCEPROP 2 LASTPIN (500 -1475) $PN 7
J 0
(510 -1465);
DISPLAY 0.680851 (510 -1465);
PAINT MONO (510 -1465);
FORCEPROP 2 LASTPIN (-450 -1525) $PN 24
J 2
(-460 -1515);
DISPLAY 0.680851 (-460 -1515);
PAINT MONO (-460 -1515);
FORCEPROP 2 LASTPIN (-450 -1425) $PN 4
J 2
(-460 -1415);
DISPLAY 0.680851 (-460 -1415);
PAINT MONO (-460 -1415);
FORCEPROP 2 LASTPIN (-450 -1225) $PN 17
J 2
(-460 -1215);
DISPLAY 0.680851 (-460 -1215);
PAINT MONO (-460 -1215);
FORCEPROP 2 LASTPIN (500 -1775) $PN 19
J 0
(510 -1765);
DISPLAY 0.680851 (510 -1765);
PAINT MONO (510 -1765);
FORCEPROP 2 LASTPIN (-450 -1025) $PN 21
J 2
(-460 -1015);
DISPLAY 0.680851 (-460 -1015);
PAINT MONO (-460 -1015);
FORCEPROP 2 LASTPIN (-450 -475) $PN 9
J 2
(-460 -465);
DISPLAY 0.680851 (-460 -465);
PAINT MONO (-460 -465);
FORCEPROP 2 LASTPIN (-450 -525) $PN 10
J 2
(-460 -515);
DISPLAY 0.680851 (-460 -515);
PAINT MONO (-460 -515);
FORCEPROP 2 LASTPIN (-450 -575) $PN 11
J 2
(-460 -565);
DISPLAY 0.680851 (-460 -565);
PAINT MONO (-460 -565);
FORCEPROP 2 LASTPIN (-450 -625) $PN 12
J 2
(-460 -615);
DISPLAY 0.680851 (-460 -615);
PAINT MONO (-460 -615);
FORCEPROP 2 LASTPIN (-450 -675) $PN 13
J 2
(-460 -665);
DISPLAY 0.680851 (-460 -665);
PAINT MONO (-460 -665);
FORCEPROP 2 LASTPIN (-450 -725) $PN 14
J 2
(-460 -715);
DISPLAY 0.680851 (-460 -715);
PAINT MONO (-460 -715);
FORCEPROP 2 LASTPIN (-450 -775) $PN 15
J 2
(-460 -765);
DISPLAY 0.680851 (-460 -765);
PAINT MONO (-460 -765);
FORCEPROP 2 LASTPIN (-450 -825) $PN 16
J 2
(-460 -815);
DISPLAY 0.680851 (-460 -815);
PAINT MONO (-460 -815);
FORCEPROP 2 LASTPIN (-450 -875) $PN 33
J 2
(-460 -865);
DISPLAY 0.680851 (-460 -865);
PAINT MONO (-460 -865);
FORCEPROP 2 LASTPIN (500 -475) $PN 1
J 0
(510 -465);
DISPLAY 0.680851 (510 -465);
PAINT MONO (510 -465);
FORCEPROP 2 LASTPIN (500 -525) $PN 2
J 0
(510 -515);
DISPLAY 0.680851 (510 -515);
PAINT MONO (510 -515);
FORCEPROP 2 LASTPIN (500 -575) $PN 25
J 0
(510 -565);
DISPLAY 0.680851 (510 -565);
PAINT MONO (510 -565);
FORCEPROP 2 LASTPIN (500 -625) $PN 26
J 0
(510 -615);
DISPLAY 0.680851 (510 -615);
PAINT MONO (510 -615);
FORCEPROP 2 LASTPIN (500 -675) $PN 27
J 0
(510 -665);
DISPLAY 0.680851 (510 -665);
PAINT MONO (510 -665);
FORCEPROP 2 LASTPIN (500 -725) $PN 28
J 0
(510 -715);
DISPLAY 0.680851 (510 -715);
PAINT MONO (510 -715);
FORCEPROP 2 LASTPIN (500 -775) $PN 29
J 0
(510 -765);
DISPLAY 0.680851 (510 -765);
PAINT MONO (510 -765);
FORCEPROP 2 LASTPIN (500 -825) $PN 30
J 0
(510 -815);
DISPLAY 0.680851 (510 -815);
PAINT MONO (510 -815);
FORCEPROP 2 LASTPIN (500 -875) $PN 31
J 0
(510 -865);
DISPLAY 0.680851 (510 -865);
PAINT MONO (510 -865);
FORCEPROP 2 LASTPIN (500 -925) $PN 32
J 0
(510 -915);
DISPLAY 0.680851 (510 -915);
PAINT MONO (510 -915);
FORCEPROP 2 LASTPIN (500 -1675) $PN 18
J 0
(510 -1665);
DISPLAY 0.680851 (510 -1665);
PAINT MONO (510 -1665);
FORCEPROP 2 LAST VALUE MP5991GLU-Z
J 0
(-300 -300);
DISPLAY 1.021277 (-300 -300);
FORCEPROP 1 LAST MATERIAL IC
J 0
(-300 -400);
DISPLAY 0.723404 (-300 -400);
PAINT GREEN (-300 -400);
FORCEPROP 1 LAST PART_NUMBER AL005991A00
J 0
(-300 -350);
DISPLAY 0.723404 (-300 -350);
PAINT GREEN (-300 -350);
FORCEPROP 2 LAST PART_TYPE SMLF
J 0
(-300 -250);
DISPLAY 1.021277 (-300 -250);
FORCEPROP 2 LAST SEC_TYPE 
J 0
(-275 25);
DISPLAY 1.021277 (-275 25);
DISPLAY INVISIBLE (-275 25);
FORCEPROP 2 LAST CDS_LIB pure_quanta
J 0
(25 -1200);
DISPLAY INVISIBLE (25 -1200);
FORCEPROP 1 LAST CDS_LMAN_SYM_OUTLINE -325,775,325,-775
J 0
(25 -1200);
DISPLAY 0.468085 (25 -1200);
PAINT GREEN (25 -1200);
DISPLAY INVISIBLE (25 -1200);
FORCEPROP 1 LAST NEEDS_NO_SIZE TRUE
J 0
(25 -1200);
DISPLAY 0.723404 (25 -1200);
PAINT GREEN (25 -1200);
DISPLAY INVISIBLE (25 -1200);
FORCEPROP 1 LAST PATH I17
J 0
(25 -1200);
DISPLAY 0.723404 (25 -1200);
PAINT GREEN (25 -1200);
DISPLAY INVISIBLE (25 -1200);
FORCEADD UNIVERSAL_POWER..1
(-950 -325);
FORCEPROP 3 LASTPIN (-950 -375) SIG_NAME P12V_PSU\g
J 0
(-940 -365);
DISPLAY 0.659574 (-940 -365);
PAINT MONO (-940 -365);
DISPLAY INVISIBLE (-940 -365);
FORCEPROP 1 LAST HDL_POWER P12V_PSU
J 1
(-950 -275);
DISPLAY 0.723404 (-950 -275);
PAINT GREEN (-950 -275);
FORCEPROP 2 LAST ROOM AUX_SW
J 0
(-950 -225);
DISPLAY 0.617021 (-950 -225);
FORCEPROP 2 LAST BOM_COST MIO_VRD_SB
J 0
(-950 -225);
DISPLAY 0.617021 (-950 -225);
PAINT PURPLE (-950 -225);
DISPLAY INVISIBLE (-950 -225);
FORCEPROP 2 LAST CDS_LIB pure_quanta_power
J 0
(-950 -325);
DISPLAY INVISIBLE (-950 -325);
FORCEPROP 1 LAST PATH I18
J 0
(-900 -300);
DISPLAY 0.872340 (-900 -300);
PAINT AQUA (-900 -300);
DISPLAY INVISIBLE (-900 -300);
FORCEADD UNIVERSAL_GND..1
(-3600 1175);
FORCEPROP 3 LASTPIN (-3600 1225) SIG_NAME AGND_HSC\g
J 0
(-3590 1235);
DISPLAY 0.659574 (-3590 1235);
PAINT MONO (-3590 1235);
DISPLAY INVISIBLE (-3590 1235);
FORCEPROP 1 LAST HDL_POWER AGND_HSC
J 1
(-3575 1100);
DISPLAY 0.723404 (-3575 1100);
PAINT GREEN (-3575 1100);
FORCEPROP 2 LAST CDS_LIB pure_quanta_power
J 0
(-3600 1175);
DISPLAY INVISIBLE (-3600 1175);
FORCEPROP 1 LAST PATH I19
J 0
(-3525 1175);
DISPLAY 0.872340 (-3525 1175);
PAINT AQUA (-3525 1175);
DISPLAY INVISIBLE (-3525 1175);
FORCEADD Q_CAP..1
(-2700 -1950);
FORCEPROP 1 LAST LOCATION PC2225
J 0
(-2625 -1850);
DISPLAY 0.723404 (-2625 -1850);
PAINT AQUA (-2625 -1850);
FORCEPROP 0 LAST $SEC 1
J 0
(-2625 -1800);
DISPLAY 0.680851 (-2625 -1800);
PAINT MONO (-2625 -1800);
DISPLAY INVISIBLE (-2625 -1800);
FORCEPROP 0 LAST CDS_SEC 1
J 0
(-2625 -1800);
DISPLAY 1.021277 (-2625 -1800);
DISPLAY INVISIBLE (-2625 -1800);
FORCEPROP 1 LASTPIN (-2700 -1850) $PN 1
J 0
(-2690 -1870);
DISPLAY 0.787234 (-2690 -1870);
PAINT MONO (-2690 -1870);
FORCEPROP 1 LASTPIN (-2700 -2050) $PN 2
J 0
(-2690 -2070);
DISPLAY 0.787234 (-2690 -2070);
PAINT MONO (-2690 -2070);
FORCEPROP 1 LAST VALUE 220PF
J 0
(-2625 -1900);
DISPLAY 0.723404 (-2625 -1900);
PAINT SKYBLUE (-2625 -1900);
FORCEPROP 1 LAST PART_NUMBER TMP_QCH12206KB14
J 0
(-2625 -2050);
DISPLAY 0.723404 (-2625 -2050);
PAINT WHITE (-2625 -2050);
FORCEPROP 1 LAST PACK_TYPE 0402
J 0
(-2625 -2100);
DISPLAY 0.723404 (-2625 -2100);
PAINT SKYBLUE (-2625 -2100);
FORCEPROP 1 LAST MATERIAL EMPTY
J 0
(-2625 -2000);
DISPLAY 0.723404 (-2625 -2000);
PAINT RED (-2625 -2000);
FORCEPROP 1 LAST VOLTAGE 50V
J 0
(-2625 -1950);
DISPLAY 0.723404 (-2625 -1950);
PAINT SKYBLUE (-2625 -1950);
FORCEPROP 1 LAST TOLERANCE 10%
J 0
(-2650 -2000);
DISPLAY 0.978723 (-2650 -2000);
PAINT SKYBLUE (-2650 -2000);
DISPLAY INVISIBLE (-2650 -2000);
FORCEPROP 2 LAST CDS_LIB pure_quanta
J 0
(-2700 -1950);
DISPLAY INVISIBLE (-2700 -1950);
FORCEPROP 1 LAST PATH I2
J 0
(-2650 -1800);
DISPLAY 0.978723 (-2650 -1800);
PAINT WHITE (-2650 -1800);
DISPLAY INVISIBLE (-2650 -1800);
FORCEADD Q_CAP..1
(-3600 1475);
FORCEPROP 1 LAST LOCATION PC3272
J 0
(-3525 1625);
DISPLAY 0.723404 (-3525 1625);
PAINT AQUA (-3525 1625);
FORCEPROP 0 LAST $SEC 1
J 0
(-3525 1675);
DISPLAY 0.680851 (-3525 1675);
PAINT MONO (-3525 1675);
DISPLAY INVISIBLE (-3525 1675);
FORCEPROP 0 LAST CDS_SEC 1
J 0
(-3525 1675);
DISPLAY 1.021277 (-3525 1675);
DISPLAY INVISIBLE (-3525 1675);
FORCEPROP 1 LASTPIN (-3600 1575) $PN 1
J 0
(-3590 1555);
DISPLAY 0.787234 (-3590 1555);
PAINT MONO (-3590 1555);
FORCEPROP 1 LASTPIN (-3600 1375) $PN 2
J 0
(-3590 1355);
DISPLAY 0.787234 (-3590 1355);
PAINT MONO (-3590 1355);
FORCEPROP 1 LAST VOLTAGE 25V
J 0
(-3525 1525);
DISPLAY 0.723404 (-3525 1525);
PAINT SKYBLUE (-3525 1525);
FORCEPROP 1 LAST PACK_TYPE C0402
J 0
(-3525 1375);
DISPLAY 0.723404 (-3525 1375);
PAINT SKYBLUE (-3525 1375);
FORCEPROP 1 LAST MATERIAL X6S
J 0
(-3525 1475);
DISPLAY 0.723404 (-3525 1475);
PAINT SKYBLUE (-3525 1475);
FORCEPROP 1 LAST PART_NUMBER CH5104KEB02
J 0
(-3525 1425);
DISPLAY 0.723404 (-3525 1425);
PAINT WHITE (-3525 1425);
FORCEPROP 1 LAST VALUE 1UF
J 0
(-3525 1575);
DISPLAY 0.723404 (-3525 1575);
PAINT SKYBLUE (-3525 1575);
FORCEPROP 2 LAST CDS_LIB pure_quanta
J 0
(-3600 1475);
DISPLAY INVISIBLE (-3600 1475);
FORCEPROP 1 LAST TOLERANCE 10%
J 0
(-3550 1425);
DISPLAY 0.978723 (-3550 1425);
PAINT SKYBLUE (-3550 1425);
DISPLAY INVISIBLE (-3550 1425);
FORCEPROP 1 LAST PATH I20
J 0
(-3550 1625);
DISPLAY 0.978723 (-3550 1625);
PAINT WHITE (-3550 1625);
DISPLAY INVISIBLE (-3550 1625);
FORCEADD Q_RES..1
R 1
(-3600 1950);
FORCEPROP 1 LAST LOCATION PR3980
J 0
(-3525 2100);
DISPLAY 0.723404 (-3525 2100);
PAINT AQUA (-3525 2100);
FORCEPROP 0 LAST $SEC 1
R 1
J 0
(-3525 2150);
DISPLAY 0.680851 (-3525 2150);
PAINT MONO (-3525 2150);
DISPLAY INVISIBLE (-3525 2150);
FORCEPROP 0 LAST CDS_SEC 1
R 1
J 0
(-3525 2150);
DISPLAY 1.021277 (-3525 2150);
DISPLAY INVISIBLE (-3525 2150);
FORCEPROP 1 LASTPIN (-3600 1850) $PN 1
R 1
J 0
(-3612 1862);
DISPLAY 0.787234 (-3612 1862);
PAINT MONO (-3612 1862);
FORCEPROP 1 LASTPIN (-3600 2050) $PN 2
R 1
J 0
(-3612 2012);
DISPLAY 0.787234 (-3612 2012);
PAINT MONO (-3612 2012);
FORCEPROP 1 LAST MATERIAL CHIP
J 0
(-3525 1950);
DISPLAY 0.787234 (-3525 1950);
PAINT SKYBLUE (-3525 1950);
FORCEPROP 1 LAST PART_NUMBER CS00002JB13
J 0
(-3525 1850);
DISPLAY 0.723404 (-3525 1850);
PAINT WHITE (-3525 1850);
FORCEPROP 1 LAST WATTAGE 1/16W
J 0
(-3525 1900);
DISPLAY 0.723404 (-3525 1900);
PAINT SKYBLUE (-3525 1900);
FORCEPROP 1 LAST PACK_TYPE 0402LF
J 0
(-3525 1800);
DISPLAY 0.723404 (-3525 1800);
PAINT SKYBLUE (-3525 1800);
FORCEPROP 1 LAST TOLERANCE 5%
J 0
(-3525 2000);
DISPLAY 0.723404 (-3525 2000);
PAINT SKYBLUE (-3525 2000);
FORCEPROP 1 LAST VALUE 0
R 2
J 0
(-3500 2075);
DISPLAY 0.723404 (-3500 2075);
PAINT SKYBLUE (-3500 2075);
FORCEPROP 2 LAST CDS_LIB pure_quanta
J 0
(-3600 1950);
DISPLAY INVISIBLE (-3600 1950);
FORCEPROP 1 LAST PATH I21
R 1
J 0
(-3750 1900);
DISPLAY 0.978723 (-3750 1900);
PAINT WHITE (-3750 1900);
DISPLAY INVISIBLE (-3750 1900);
FORCEADD OFFPAGE..4
R 2
(-2875 1350);
FORCEPROP 2 LAST $XR2 303 
J 0
(-3157 1314);
DISPLAY 0.638298 (-3157 1314);
PAINT MONO (-3157 1314);
FORCEPROP 2 LAST $XR1 302 
J 0
(-3277 1350);
DISPLAY 0.638298 (-3277 1350);
PAINT MONO (-3277 1350);
FORCEPROP 2 LAST $XR0 301 
J 0
(-3157 1350);
DISPLAY 0.638298 (-3157 1350);
PAINT MONO (-3157 1350);
FORCEPROP 2 LAST CDS_LIB standard
J 0
(-2875 1350);
DISPLAY INVISIBLE (-2875 1350);
FORCEPROP 1 LAST OFFPAGE TRUE
J 2
(-3200 1225);
DISPLAY 0.872340 (-3200 1225);
PAINT GREEN (-3200 1225);
DISPLAY INVISIBLE (-3200 1225);
FORCEPROP 1 LAST COMMENT_BODY TRUE
J 2
(-2850 1250);
DISPLAY 0.872340 (-2850 1250);
PAINT GREEN (-2850 1250);
DISPLAY INVISIBLE (-2850 1250);
FORCEPROP 2 LAST PATH I22
J 0
(-3150 1400);
DISPLAY 1.021277 (-3150 1400);
DISPLAY INVISIBLE (-3150 1400);
FORCEADD UNIVERSAL_GND..1
(-2700 525);
FORCEPROP 3 LASTPIN (-2700 575) SIG_NAME AGND_HSC\g
J 0
(-2690 585);
DISPLAY 0.659574 (-2690 585);
PAINT MONO (-2690 585);
DISPLAY INVISIBLE (-2690 585);
FORCEPROP 1 LAST HDL_POWER AGND_HSC
J 1
(-2675 450);
DISPLAY 0.723404 (-2675 450);
PAINT GREEN (-2675 450);
FORCEPROP 2 LAST CDS_LIB pure_quanta_power
J 0
(-2700 525);
DISPLAY INVISIBLE (-2700 525);
FORCEPROP 1 LAST PATH I23
J 0
(-2625 525);
DISPLAY 0.872340 (-2625 525);
PAINT AQUA (-2625 525);
DISPLAY INVISIBLE (-2625 525);
FORCEADD Q_CAP..1
(-2700 825);
FORCEPROP 1 LAST LOCATION PC2224
J 0
(-2625 925);
DISPLAY 0.723404 (-2625 925);
PAINT AQUA (-2625 925);
FORCEPROP 0 LAST $SEC 1
J 0
(-2625 975);
DISPLAY 0.680851 (-2625 975);
PAINT MONO (-2625 975);
DISPLAY INVISIBLE (-2625 975);
FORCEPROP 0 LAST CDS_SEC 1
J 0
(-2625 975);
DISPLAY 1.021277 (-2625 975);
DISPLAY INVISIBLE (-2625 975);
FORCEPROP 1 LASTPIN (-2700 925) $PN 1
J 0
(-2690 905);
DISPLAY 0.787234 (-2690 905);
PAINT MONO (-2690 905);
FORCEPROP 1 LASTPIN (-2700 725) $PN 2
J 0
(-2690 705);
DISPLAY 0.787234 (-2690 705);
PAINT MONO (-2690 705);
FORCEPROP 1 LAST VALUE 220PF
J 0
(-2625 875);
DISPLAY 0.723404 (-2625 875);
PAINT SKYBLUE (-2625 875);
FORCEPROP 1 LAST MATERIAL EMPTY
J 0
(-2625 775);
DISPLAY 0.723404 (-2625 775);
PAINT RED (-2625 775);
FORCEPROP 1 LAST PART_NUMBER TMP_QCH12206KB14
J 0
(-2625 725);
DISPLAY 0.723404 (-2625 725);
PAINT WHITE (-2625 725);
FORCEPROP 1 LAST VOLTAGE 50V
J 0
(-2625 825);
DISPLAY 0.723404 (-2625 825);
PAINT SKYBLUE (-2625 825);
FORCEPROP 1 LAST PACK_TYPE 0402
J 0
(-2625 675);
DISPLAY 0.723404 (-2625 675);
PAINT SKYBLUE (-2625 675);
FORCEPROP 1 LAST TOLERANCE 10%
J 0
(-2650 775);
DISPLAY 0.978723 (-2650 775);
PAINT SKYBLUE (-2650 775);
DISPLAY INVISIBLE (-2650 775);
FORCEPROP 2 LAST CDS_LIB pure_quanta
J 0
(-2700 825);
DISPLAY INVISIBLE (-2700 825);
FORCEPROP 1 LAST PATH I24
J 0
(-2650 975);
DISPLAY 0.978723 (-2650 975);
PAINT WHITE (-2650 975);
DISPLAY INVISIBLE (-2650 975);
FORCEADD UNIVERSAL_GND..1
(-2725 1575);
FORCEPROP 3 LASTPIN (-2725 1625) SIG_NAME AGND_HSC\g
J 0
(-2715 1635);
DISPLAY 0.659574 (-2715 1635);
PAINT MONO (-2715 1635);
DISPLAY INVISIBLE (-2715 1635);
FORCEPROP 1 LAST HDL_POWER AGND_HSC
J 1
(-2700 1500);
DISPLAY 0.723404 (-2700 1500);
PAINT GREEN (-2700 1500);
FORCEPROP 2 LAST CDS_LIB pure_quanta_power
J 0
(-2725 1575);
DISPLAY INVISIBLE (-2725 1575);
FORCEPROP 1 LAST PATH I25
J 0
(-2650 1575);
DISPLAY 0.872340 (-2650 1575);
PAINT AQUA (-2650 1575);
DISPLAY INVISIBLE (-2650 1575);
FORCEADD OFFPAGE..4
R 2
(-2050 1250);
FORCEPROP 2 LAST $XR2 303 
J 0
(-2542 1250);
DISPLAY 0.638298 (-2542 1250);
PAINT MONO (-2542 1250);
FORCEPROP 2 LAST $XR1 302 
J 0
(-2422 1250);
DISPLAY 0.638298 (-2422 1250);
PAINT MONO (-2422 1250);
FORCEPROP 2 LAST $XR0 301 
J 0
(-2302 1250);
DISPLAY 0.638298 (-2302 1250);
PAINT MONO (-2302 1250);
FORCEPROP 2 LAST CDS_LIB standard
J 0
(-2050 1250);
DISPLAY INVISIBLE (-2050 1250);
FORCEPROP 1 LAST OFFPAGE TRUE
J 2
(-2375 1125);
DISPLAY 0.872340 (-2375 1125);
PAINT GREEN (-2375 1125);
DISPLAY INVISIBLE (-2375 1125);
FORCEPROP 1 LAST COMMENT_BODY TRUE
J 2
(-2025 1150);
DISPLAY 0.872340 (-2025 1150);
PAINT GREEN (-2025 1150);
DISPLAY INVISIBLE (-2025 1150);
FORCEPROP 2 LAST PATH I26
J 0
(-2300 1300);
DISPLAY 1.021277 (-2300 1300);
DISPLAY INVISIBLE (-2300 1300);
FORCEADD OFFPAGE..4
R 2
(-2025 1475);
FORCEPROP 2 LAST $XR2 303 
J 0
(-2517 1475);
DISPLAY 0.638298 (-2517 1475);
PAINT MONO (-2517 1475);
FORCEPROP 2 LAST $XR1 302 
J 0
(-2397 1475);
DISPLAY 0.638298 (-2397 1475);
PAINT MONO (-2397 1475);
FORCEPROP 2 LAST $XR0 301 
J 0
(-2277 1475);
DISPLAY 0.638298 (-2277 1475);
PAINT MONO (-2277 1475);
FORCEPROP 2 LAST CDS_LIB standard
J 0
(-2025 1475);
DISPLAY INVISIBLE (-2025 1475);
FORCEPROP 1 LAST OFFPAGE TRUE
J 2
(-2350 1350);
DISPLAY 0.872340 (-2350 1350);
PAINT GREEN (-2350 1350);
DISPLAY INVISIBLE (-2350 1350);
FORCEPROP 1 LAST COMMENT_BODY TRUE
J 2
(-2000 1375);
DISPLAY 0.872340 (-2000 1375);
PAINT GREEN (-2000 1375);
DISPLAY INVISIBLE (-2000 1375);
FORCEPROP 2 LAST PATH I27
J 0
(-2275 1525);
DISPLAY 1.021277 (-2275 1525);
DISPLAY INVISIBLE (-2275 1525);
FORCEADD Q_RES..1
(-1900 1650);
FORCEPROP 1 LAST LOCATION PR3982
J 0
(-2175 1650);
DISPLAY 0.723404 (-2175 1650);
PAINT AQUA (-2175 1650);
FORCEPROP 0 LAST $SEC 1
J 0
(-1850 1725);
DISPLAY 0.680851 (-1850 1725);
PAINT MONO (-1850 1725);
DISPLAY INVISIBLE (-1850 1725);
FORCEPROP 0 LAST CDS_SEC 1
J 0
(-1850 1725);
DISPLAY 1.021277 (-1850 1725);
DISPLAY INVISIBLE (-1850 1725);
FORCEPROP 1 LASTPIN (-2000 1650) $PN 1
J 0
(-1988 1662);
DISPLAY 0.787234 (-1988 1662);
PAINT MONO (-1988 1662);
FORCEPROP 1 LASTPIN (-1800 1650) $PN 2
J 0
(-1838 1662);
DISPLAY 0.787234 (-1838 1662);
PAINT MONO (-1838 1662);
FORCEPROP 1 LAST MATERIAL CHIP
J 0
(-1850 1525);
DISPLAY 0.723404 (-1850 1525);
PAINT SKYBLUE (-1850 1525);
FORCEPROP 1 LAST PACK_TYPE 0402LF
J 0
(-1775 1575);
DISPLAY 0.723404 (-1775 1575);
PAINT SKYBLUE (-1775 1575);
FORCEPROP 1 LAST TOLERANCE 1%
J 0
(-1875 1575);
DISPLAY 0.723404 (-1875 1575);
PAINT SKYBLUE (-1875 1575);
FORCEPROP 1 LAST VALUE 120K
J 2
(-1925 1575);
DISPLAY 0.723404 (-1925 1575);
PAINT SKYBLUE (-1925 1575);
FORCEPROP 1 LAST PART_NUMBER CS41202FB05
J 0
(-1750 1650);
DISPLAY 0.723404 (-1750 1650);
PAINT WHITE (-1750 1650);
FORCEPROP 1 LAST WATTAGE 1/16W
J 2
(-1875 1525);
DISPLAY 0.723404 (-1875 1525);
PAINT SKYBLUE (-1875 1525);
FORCEPROP 2 LAST CDS_LIB pure_quanta
J 0
(-1900 1650);
DISPLAY INVISIBLE (-1900 1650);
FORCEPROP 1 LAST PATH I28
J 0
(-1950 1800);
DISPLAY 0.978723 (-1950 1800);
PAINT WHITE (-1950 1800);
DISPLAY INVISIBLE (-1950 1800);
FORCEADD UNIVERSAL_POWER..1
(-3600 2200);
FORCEPROP 3 LASTPIN (-3600 2150) SIG_NAME HSC_VDD\g
J 0
(-3590 2160);
DISPLAY 0.659574 (-3590 2160);
PAINT MONO (-3590 2160);
DISPLAY INVISIBLE (-3590 2160);
FORCEPROP 1 LAST HDL_POWER HSC_VDD
J 1
(-3600 2250);
DISPLAY 0.723404 (-3600 2250);
PAINT GREEN (-3600 2250);
FORCEPROP 2 LAST ROOM AUX_SW
J 0
(-3600 2300);
DISPLAY 0.617021 (-3600 2300);
FORCEPROP 2 LAST CDS_LIB pure_quanta_power
J 0
(-3600 2200);
DISPLAY INVISIBLE (-3600 2200);
FORCEPROP 2 LAST BOM_COST MIO_VRD_SB
J 0
(-3600 2300);
DISPLAY 0.617021 (-3600 2300);
PAINT PURPLE (-3600 2300);
DISPLAY INVISIBLE (-3600 2300);
FORCEPROP 1 LAST PATH I29
J 0
(-3550 2225);
DISPLAY 0.872340 (-3550 2225);
PAINT AQUA (-3550 2225);
DISPLAY INVISIBLE (-3550 2225);
FORCEADD UNIVERSAL_GND..1
(-3575 -1600);
FORCEPROP 3 LASTPIN (-3575 -1550) SIG_NAME AGND_HSC\g
J 0
(-3565 -1540);
DISPLAY 0.659574 (-3565 -1540);
PAINT MONO (-3565 -1540);
DISPLAY INVISIBLE (-3565 -1540);
FORCEPROP 1 LAST HDL_POWER AGND_HSC
J 1
(-3550 -1675);
DISPLAY 0.723404 (-3550 -1675);
PAINT GREEN (-3550 -1675);
FORCEPROP 2 LAST CDS_LIB pure_quanta_power
J 0
(-3575 -1600);
DISPLAY INVISIBLE (-3575 -1600);
FORCEPROP 1 LAST PATH I3
J 0
(-3500 -1600);
DISPLAY 0.872340 (-3500 -1600);
PAINT AQUA (-3500 -1600);
DISPLAY INVISIBLE (-3500 -1600);
FORCEADD Q_CAP..1
(-1950 825);
FORCEPROP 1 LAST LOCATION PC2350
J 0
(-1875 925);
DISPLAY 0.808511 (-1875 925);
PAINT AQUA (-1875 925);
FORCEPROP 0 LAST $SEC 1
J 0
(-1875 975);
DISPLAY 0.680851 (-1875 975);
PAINT MONO (-1875 975);
DISPLAY INVISIBLE (-1875 975);
FORCEPROP 0 LAST CDS_SEC 1
J 0
(-1875 975);
DISPLAY 1.021277 (-1875 975);
DISPLAY INVISIBLE (-1875 975);
FORCEPROP 1 LASTPIN (-1950 925) $PN 1
J 0
(-1940 905);
DISPLAY 0.787234 (-1940 905);
PAINT MONO (-1940 905);
FORCEPROP 1 LASTPIN (-1950 725) $PN 2
J 0
(-1940 705);
DISPLAY 0.787234 (-1940 705);
PAINT MONO (-1940 705);
FORCEPROP 1 LAST PART_NUMBER CH21006KB16
J 0
(-1875 725);
DISPLAY 0.723404 (-1875 725);
PAINT WHITE (-1875 725);
FORCEPROP 1 LAST VALUE 1NF
J 0
(-1875 875);
DISPLAY 0.723404 (-1875 875);
PAINT SKYBLUE (-1875 875);
FORCEPROP 1 LAST MATERIAL EMPTY
J 0
(-1875 775);
DISPLAY 0.723404 (-1875 775);
PAINT RED (-1875 775);
FORCEPROP 1 LAST PACK_TYPE 0402
J 0
(-1875 675);
DISPLAY 0.723404 (-1875 675);
PAINT SKYBLUE (-1875 675);
FORCEPROP 1 LAST VOLTAGE 50V
J 0
(-1875 825);
DISPLAY 0.723404 (-1875 825);
PAINT SKYBLUE (-1875 825);
FORCEPROP 2 LAST CDS_LIB pure_quanta
J 0
(-1950 825);
DISPLAY INVISIBLE (-1950 825);
FORCEPROP 1 LAST TOLERANCE 10%
J 0
(-1900 775);
DISPLAY 0.978723 (-1900 775);
PAINT SKYBLUE (-1900 775);
DISPLAY INVISIBLE (-1900 775);
FORCEPROP 1 LAST PATH I30
J 0
(-1900 975);
DISPLAY 0.978723 (-1900 975);
PAINT WHITE (-1900 975);
DISPLAY INVISIBLE (-1900 975);
FORCEADD Q_RES..2
(-1475 825);
FORCEPROP 1 LAST LOCATION PR3986
J 0
(-1420 975);
DISPLAY 0.723404 (-1420 975);
PAINT AQUA (-1420 975);
FORCEPROP 0 LAST $SEC 1
J 0
(-1400 1025);
DISPLAY 0.680851 (-1400 1025);
PAINT MONO (-1400 1025);
DISPLAY INVISIBLE (-1400 1025);
FORCEPROP 0 LAST CDS_SEC 1
J 0
(-1400 1025);
DISPLAY 1.021277 (-1400 1025);
DISPLAY INVISIBLE (-1400 1025);
FORCEPROP 1 LASTPIN (-1475 925) $PN 1
J 0
(-1470 887);
DISPLAY 0.787234 (-1470 887);
PAINT MONO (-1470 887);
FORCEPROP 1 LASTPIN (-1475 725) $PN 2
J 0
(-1470 735);
DISPLAY 0.787234 (-1470 735);
PAINT MONO (-1470 735);
FORCEPROP 1 LAST PACK_TYPE 0402LF
J 0
(-1425 675);
DISPLAY 0.723404 (-1425 675);
PAINT SKYBLUE (-1425 675);
FORCEPROP 1 LAST VALUE 2K
J 0
(-1420 925);
DISPLAY 0.723404 (-1420 925);
PAINT SKYBLUE (-1420 925);
FORCEPROP 1 LAST TOLERANCE 0.1%
J 0
(-1420 875);
DISPLAY 0.723404 (-1420 875);
PAINT SKYBLUE (-1420 875);
FORCEPROP 1 LAST PART_NUMBER CS22002BB07
J 0
(-1425 725);
DISPLAY 0.723404 (-1425 725);
PAINT WHITE (-1425 725);
FORCEPROP 1 LAST WATTAGE 1/16W
J 0
(-1425 825);
DISPLAY 0.723404 (-1425 825);
PAINT SKYBLUE (-1425 825);
FORCEPROP 1 LAST MATERIAL CHIP
J 0
(-1425 775);
DISPLAY 0.723404 (-1425 775);
PAINT SKYBLUE (-1425 775);
FORCEPROP 2 LAST CDS_LIB pure_quanta
J 0
(-1475 825);
DISPLAY INVISIBLE (-1475 825);
FORCEPROP 1 LAST PATH I31
J 0
(-1425 1000);
DISPLAY 0.978723 (-1425 1000);
PAINT WHITE (-1425 1000);
DISPLAY INVISIBLE (-1425 1000);
FORCEADD OFFPAGE..5
(-1050 1050);
FORCEPROP 2 LAST $XR2 301 
J 0
(-1305 1014);
DISPLAY 0.638298 (-1305 1014);
PAINT MONO (-1305 1014);
FORCEPROP 2 LAST $XR1 303 
J 0
(-1425 1050);
DISPLAY 0.638298 (-1425 1050);
PAINT MONO (-1425 1050);
FORCEPROP 2 LAST $XR0 302 
J 0
(-1305 1050);
DISPLAY 0.638298 (-1305 1050);
PAINT MONO (-1305 1050);
FORCEPROP 2 LAST CDS_LIB standard
J 0
(-1050 1050);
DISPLAY INVISIBLE (-1050 1050);
FORCEPROP 1 LAST OFFPAGE TRUE
J 0
(-725 925);
DISPLAY 0.872340 (-725 925);
PAINT AQUA (-725 925);
DISPLAY INVISIBLE (-725 925);
FORCEPROP 1 LAST COMMENT_BODY TRUE
J 0
(-950 975);
DISPLAY 1.170213 (-950 975);
PAINT GREEN (-950 975);
DISPLAY INVISIBLE (-950 975);
FORCEPROP 2 LAST PATH I32
J 0
(-1300 1100);
DISPLAY 1.021277 (-1300 1100);
DISPLAY INVISIBLE (-1300 1100);
FORCEADD Q_RES..1
(-1325 1475);
FORCEPROP 1 LAST LOCATION PR3988
J 0
(-1625 1475);
DISPLAY 0.723404 (-1625 1475);
PAINT AQUA (-1625 1475);
FORCEPROP 0 LAST $SEC 1
J 0
(-1200 1550);
DISPLAY 0.680851 (-1200 1550);
PAINT MONO (-1200 1550);
DISPLAY INVISIBLE (-1200 1550);
FORCEPROP 0 LAST CDS_SEC 1
J 0
(-1200 1550);
DISPLAY 1.021277 (-1200 1550);
DISPLAY INVISIBLE (-1200 1550);
FORCEPROP 1 LASTPIN (-1425 1475) $PN 1
J 0
(-1413 1487);
DISPLAY 0.787234 (-1413 1487);
PAINT MONO (-1413 1487);
FORCEPROP 1 LASTPIN (-1225 1475) $PN 2
J 0
(-1263 1487);
DISPLAY 0.787234 (-1263 1487);
PAINT MONO (-1263 1487);
FORCEPROP 1 LAST MATERIAL CHIP
J 0
(-1150 1375);
DISPLAY 0.723404 (-1150 1375);
PAINT SKYBLUE (-1150 1375);
FORCEPROP 1 LAST PACK_TYPE 0402LF
J 0
(-1400 1375);
DISPLAY 0.723404 (-1400 1375);
PAINT SKYBLUE (-1400 1375);
FORCEPROP 1 LAST PART_NUMBER CS00002JB13
J 0
(-1650 1425);
DISPLAY 0.723404 (-1650 1425);
PAINT WHITE (-1650 1425);
FORCEPROP 1 LAST WATTAGE 1/16W
J 2
(-1450 1375);
DISPLAY 0.723404 (-1450 1375);
PAINT SKYBLUE (-1450 1375);
FORCEPROP 1 LAST TOLERANCE 5%
J 0
(-1200 1425);
DISPLAY 0.723404 (-1200 1425);
PAINT SKYBLUE (-1200 1425);
FORCEPROP 1 LAST VALUE 0
J 2
(-1200 1500);
DISPLAY 0.723404 (-1200 1500);
PAINT SKYBLUE (-1200 1500);
FORCEPROP 2 LAST CDS_LIB pure_quanta
J 0
(-1325 1475);
DISPLAY INVISIBLE (-1325 1475);
FORCEPROP 1 LAST PATH I33
J 0
(-1375 1625);
DISPLAY 0.978723 (-1375 1625);
PAINT WHITE (-1375 1625);
DISPLAY INVISIBLE (-1375 1625);
FORCEADD Q_RES..2
(-950 825);
FORCEPROP 1 LAST LOCATION PR3990
J 0
(-895 975);
DISPLAY 0.723404 (-895 975);
PAINT AQUA (-895 975);
FORCEPROP 0 LAST $SEC 1
J 0
(-875 1025);
DISPLAY 0.680851 (-875 1025);
PAINT MONO (-875 1025);
DISPLAY INVISIBLE (-875 1025);
FORCEPROP 0 LAST CDS_SEC 1
J 0
(-875 1025);
DISPLAY 1.021277 (-875 1025);
DISPLAY INVISIBLE (-875 1025);
FORCEPROP 1 LASTPIN (-950 925) $PN 1
J 0
(-945 887);
DISPLAY 0.787234 (-945 887);
PAINT MONO (-945 887);
FORCEPROP 1 LASTPIN (-950 725) $PN 2
J 0
(-945 735);
DISPLAY 0.787234 (-945 735);
PAINT MONO (-945 735);
FORCEPROP 1 LAST PART_NUMBER CS22002BB07
J 0
(-900 725);
DISPLAY 0.723404 (-900 725);
PAINT WHITE (-900 725);
FORCEPROP 1 LAST PACK_TYPE 0402LF
J 0
(-900 675);
DISPLAY 0.723404 (-900 675);
PAINT SKYBLUE (-900 675);
FORCEPROP 1 LAST MATERIAL CHIP
J 0
(-900 775);
DISPLAY 0.723404 (-900 775);
PAINT SKYBLUE (-900 775);
FORCEPROP 1 LAST VALUE 2K
J 0
(-895 925);
DISPLAY 0.723404 (-895 925);
PAINT SKYBLUE (-895 925);
FORCEPROP 1 LAST WATTAGE 1/16W
J 0
(-900 825);
DISPLAY 0.723404 (-900 825);
PAINT SKYBLUE (-900 825);
FORCEPROP 1 LAST TOLERANCE 0.1%
J 0
(-895 875);
DISPLAY 0.723404 (-895 875);
PAINT SKYBLUE (-895 875);
FORCEPROP 2 LAST CDS_LIB pure_quanta
J 0
(-950 825);
DISPLAY INVISIBLE (-950 825);
FORCEPROP 1 LAST PATH I34
J 0
(-900 1000);
DISPLAY 0.978723 (-900 1000);
PAINT WHITE (-900 1000);
DISPLAY INVISIBLE (-900 1000);
FORCEADD MP5991GLUZ..1
(25 1575);
FORCEPROP 1 LAST LOCATION PU296
J 0
(-300 2575);
DISPLAY 1.148936 (-300 2575);
PAINT GREEN (-300 2575);
FORCEPROP 2 LAST SEC 1
J 0
(-275 2800);
DISPLAY 0.680851 (-275 2800);
PAINT MONO (-275 2800);
DISPLAY INVISIBLE (-275 2800);
FORCEPROP 2 LASTPIN (-450 1150) $PN 23
J 2
(-460 1160);
DISPLAY 0.680851 (-460 1160);
PAINT MONO (-460 1160);
FORCEPROP 2 LASTPIN (500 1500) $PN 3
J 0
(510 1510);
DISPLAY 0.680851 (510 1510);
PAINT MONO (510 1510);
FORCEPROP 2 LASTPIN (500 1400) $PN 6
J 0
(510 1410);
DISPLAY 0.680851 (510 1410);
PAINT MONO (510 1410);
FORCEPROP 2 LASTPIN (-450 850) $PN 20
J 2
(-460 860);
DISPLAY 0.680851 (-460 860);
PAINT MONO (-460 860);
FORCEPROP 2 LASTPIN (500 1200) $PN 5
J 0
(510 1210);
DISPLAY 0.680851 (510 1210);
PAINT MONO (510 1210);
FORCEPROP 2 LASTPIN (-450 1050) $PN 22
J 2
(-460 1060);
DISPLAY 0.680851 (-460 1060);
PAINT MONO (-460 1060);
FORCEPROP 2 LASTPIN (-450 1650) $PN 8
J 2
(-460 1660);
DISPLAY 0.680851 (-460 1660);
PAINT MONO (-460 1660);
FORCEPROP 2 LASTPIN (500 1300) $PN 7
J 0
(510 1310);
DISPLAY 0.680851 (510 1310);
PAINT MONO (510 1310);
FORCEPROP 2 LASTPIN (-450 1250) $PN 24
J 2
(-460 1260);
DISPLAY 0.680851 (-460 1260);
PAINT MONO (-460 1260);
FORCEPROP 2 LASTPIN (-450 1350) $PN 4
J 2
(-460 1360);
DISPLAY 0.680851 (-460 1360);
PAINT MONO (-460 1360);
FORCEPROP 2 LASTPIN (-450 1550) $PN 17
J 2
(-460 1560);
DISPLAY 0.680851 (-460 1560);
PAINT MONO (-460 1560);
FORCEPROP 2 LASTPIN (500 1000) $PN 19
J 0
(510 1010);
DISPLAY 0.680851 (510 1010);
PAINT MONO (510 1010);
FORCEPROP 2 LASTPIN (-450 1750) $PN 21
J 2
(-460 1760);
DISPLAY 0.680851 (-460 1760);
PAINT MONO (-460 1760);
FORCEPROP 2 LASTPIN (-450 2300) $PN 9
J 2
(-460 2310);
DISPLAY 0.680851 (-460 2310);
PAINT MONO (-460 2310);
FORCEPROP 2 LASTPIN (-450 2250) $PN 10
J 2
(-460 2260);
DISPLAY 0.680851 (-460 2260);
PAINT MONO (-460 2260);
FORCEPROP 2 LASTPIN (-450 2200) $PN 11
J 2
(-460 2210);
DISPLAY 0.680851 (-460 2210);
PAINT MONO (-460 2210);
FORCEPROP 2 LASTPIN (-450 2150) $PN 12
J 2
(-460 2160);
DISPLAY 0.680851 (-460 2160);
PAINT MONO (-460 2160);
FORCEPROP 2 LASTPIN (-450 2100) $PN 13
J 2
(-460 2110);
DISPLAY 0.680851 (-460 2110);
PAINT MONO (-460 2110);
FORCEPROP 2 LASTPIN (-450 2050) $PN 14
J 2
(-460 2060);
DISPLAY 0.680851 (-460 2060);
PAINT MONO (-460 2060);
FORCEPROP 2 LASTPIN (-450 2000) $PN 15
J 2
(-460 2010);
DISPLAY 0.680851 (-460 2010);
PAINT MONO (-460 2010);
FORCEPROP 2 LASTPIN (-450 1950) $PN 16
J 2
(-460 1960);
DISPLAY 0.680851 (-460 1960);
PAINT MONO (-460 1960);
FORCEPROP 2 LASTPIN (-450 1900) $PN 33
J 2
(-460 1910);
DISPLAY 0.680851 (-460 1910);
PAINT MONO (-460 1910);
FORCEPROP 2 LASTPIN (500 2300) $PN 1
J 0
(510 2310);
DISPLAY 0.680851 (510 2310);
PAINT MONO (510 2310);
FORCEPROP 2 LASTPIN (500 2250) $PN 2
J 0
(510 2260);
DISPLAY 0.680851 (510 2260);
PAINT MONO (510 2260);
FORCEPROP 2 LASTPIN (500 2200) $PN 25
J 0
(510 2210);
DISPLAY 0.680851 (510 2210);
PAINT MONO (510 2210);
FORCEPROP 2 LASTPIN (500 2150) $PN 26
J 0
(510 2160);
DISPLAY 0.680851 (510 2160);
PAINT MONO (510 2160);
FORCEPROP 2 LASTPIN (500 2100) $PN 27
J 0
(510 2110);
DISPLAY 0.680851 (510 2110);
PAINT MONO (510 2110);
FORCEPROP 2 LASTPIN (500 2050) $PN 28
J 0
(510 2060);
DISPLAY 0.680851 (510 2060);
PAINT MONO (510 2060);
FORCEPROP 2 LASTPIN (500 2000) $PN 29
J 0
(510 2010);
DISPLAY 0.680851 (510 2010);
PAINT MONO (510 2010);
FORCEPROP 2 LASTPIN (500 1950) $PN 30
J 0
(510 1960);
DISPLAY 0.680851 (510 1960);
PAINT MONO (510 1960);
FORCEPROP 2 LASTPIN (500 1900) $PN 31
J 0
(510 1910);
DISPLAY 0.680851 (510 1910);
PAINT MONO (510 1910);
FORCEPROP 2 LASTPIN (500 1850) $PN 32
J 0
(510 1860);
DISPLAY 0.680851 (510 1860);
PAINT MONO (510 1860);
FORCEPROP 2 LASTPIN (500 1100) $PN 18
J 0
(510 1110);
DISPLAY 0.680851 (510 1110);
PAINT MONO (510 1110);
FORCEPROP 2 LAST VALUE MP5991GLU-Z
J 0
(-300 2475);
DISPLAY 1.021277 (-300 2475);
FORCEPROP 1 LAST MATERIAL IC
J 0
(-300 2382);
DISPLAY 0.723404 (-300 2382);
PAINT GREEN (-300 2382);
FORCEPROP 1 LAST PART_NUMBER AL005991A00
J 0
(-300 2425);
DISPLAY 0.723404 (-300 2425);
PAINT GREEN (-300 2425);
FORCEPROP 2 LAST PART_TYPE SMLF
J 0
(-300 2525);
DISPLAY 1.021277 (-300 2525);
FORCEPROP 2 LAST SEC_TYPE 
J 0
(-275 2800);
DISPLAY 1.021277 (-275 2800);
DISPLAY INVISIBLE (-275 2800);
FORCEPROP 1 LAST NEEDS_NO_SIZE TRUE
J 0
(25 1575);
DISPLAY 0.723404 (25 1575);
PAINT GREEN (25 1575);
DISPLAY INVISIBLE (25 1575);
FORCEPROP 1 LAST CDS_LMAN_SYM_OUTLINE -325,775,325,-775
J 0
(25 1575);
DISPLAY 0.468085 (25 1575);
PAINT GREEN (25 1575);
DISPLAY INVISIBLE (25 1575);
FORCEPROP 2 LAST CDS_LIB pure_quanta
J 0
(25 1575);
DISPLAY INVISIBLE (25 1575);
FORCEPROP 1 LAST PATH I35
J 0
(25 1575);
DISPLAY 0.723404 (25 1575);
PAINT GREEN (25 1575);
DISPLAY INVISIBLE (25 1575);
FORCEADD UNIVERSAL_POWER..1
(-950 2450);
FORCEPROP 3 LASTPIN (-950 2400) SIG_NAME P12V_PSU\g
J 0
(-940 2410);
DISPLAY 0.659574 (-940 2410);
PAINT MONO (-940 2410);
DISPLAY INVISIBLE (-940 2410);
FORCEPROP 1 LAST HDL_POWER P12V_PSU
J 1
(-950 2500);
DISPLAY 0.723404 (-950 2500);
PAINT GREEN (-950 2500);
FORCEPROP 2 LAST ROOM AUX_SW
J 0
(-950 2550);
DISPLAY 0.617021 (-950 2550);
FORCEPROP 2 LAST BOM_COST MIO_VRD_SB
J 0
(-950 2550);
DISPLAY 0.617021 (-950 2550);
PAINT PURPLE (-950 2550);
DISPLAY INVISIBLE (-950 2550);
FORCEPROP 2 LAST CDS_LIB pure_quanta_power
J 0
(-950 2450);
DISPLAY INVISIBLE (-950 2450);
FORCEPROP 1 LAST PATH I36
J 0
(-900 2475);
DISPLAY 0.872340 (-900 2475);
PAINT AQUA (-900 2475);
DISPLAY INVISIBLE (-900 2475);
FORCEADD UNIVERSAL_GND..1
(1000 -2150);
FORCEPROP 3 LASTPIN (1000 -2100) SIG_NAME AGND_HSC\g
J 0
(1010 -2090);
DISPLAY 0.659574 (1010 -2090);
PAINT MONO (1010 -2090);
DISPLAY INVISIBLE (1010 -2090);
FORCEPROP 1 LAST HDL_POWER AGND_HSC
J 1
(1025 -2225);
DISPLAY 0.723404 (1025 -2225);
PAINT GREEN (1025 -2225);
FORCEPROP 2 LAST CDS_LIB pure_quanta_power
J 0
(1000 -2150);
DISPLAY INVISIBLE (1000 -2150);
FORCEPROP 1 LAST PATH I37
J 0
(1075 -2150);
DISPLAY 0.872340 (1075 -2150);
PAINT AQUA (1075 -2150);
DISPLAY INVISIBLE (1075 -2150);
FORCEADD Q_CAP..1
(1000 -1925);
FORCEPROP 1 LAST LOCATION PC2227
J 0
(1050 -1850);
DISPLAY 0.723404 (1050 -1850);
PAINT AQUA (1050 -1850);
FORCEPROP 0 LAST $SEC 1
J 0
(1050 -1800);
DISPLAY 0.680851 (1050 -1800);
PAINT MONO (1050 -1800);
DISPLAY INVISIBLE (1050 -1800);
FORCEPROP 0 LAST CDS_SEC 1
J 0
(1050 -1800);
DISPLAY 1.021277 (1050 -1800);
DISPLAY INVISIBLE (1050 -1800);
FORCEPROP 1 LASTPIN (1000 -1825) $PN 1
J 0
(1010 -1845);
DISPLAY 0.787234 (1010 -1845);
PAINT MONO (1010 -1845);
FORCEPROP 1 LASTPIN (1000 -2025) $PN 2
J 0
(1010 -2045);
DISPLAY 0.787234 (1010 -2045);
PAINT MONO (1010 -2045);
FORCEPROP 1 LAST VOLTAGE 16V
J 0
(1050 -1950);
DISPLAY 0.723404 (1050 -1950);
PAINT SKYBLUE (1050 -1950);
FORCEPROP 1 LAST MATERIAL X7R
J 0
(1050 -2000);
DISPLAY 0.723404 (1050 -2000);
PAINT SKYBLUE (1050 -2000);
FORCEPROP 1 LAST PART_NUMBER CH3683K1B09
J 0
(1050 -2050);
DISPLAY 0.723404 (1050 -2050);
PAINT WHITE (1050 -2050);
FORCEPROP 1 LAST VALUE 0.068UF
J 0
(1050 -1900);
DISPLAY 0.723404 (1050 -1900);
PAINT SKYBLUE (1050 -1900);
FORCEPROP 1 LAST PACK_TYPE 0402
J 0
(1050 -2100);
DISPLAY 0.723404 (1050 -2100);
PAINT SKYBLUE (1050 -2100);
FORCEPROP 2 LAST CDS_LIB pure_quanta
J 0
(1000 -1925);
DISPLAY INVISIBLE (1000 -1925);
FORCEPROP 1 LAST TOLERANCE 10%
J 0
(1050 -1975);
DISPLAY 0.978723 (1050 -1975);
PAINT SKYBLUE (1050 -1975);
DISPLAY INVISIBLE (1050 -1975);
FORCEPROP 1 LAST PATH I38
J 0
(1050 -1775);
DISPLAY 0.978723 (1050 -1775);
PAINT WHITE (1050 -1775);
DISPLAY INVISIBLE (1050 -1775);
FORCEADD Q_RES..1
(1500 -1375);
FORCEPROP 1 LAST LOCATION PR3995
J 0
(1200 -1375);
DISPLAY 0.723404 (1200 -1375);
PAINT AQUA (1200 -1375);
FORCEPROP 0 LAST $SEC 1
J 0
(1650 -1300);
DISPLAY 0.680851 (1650 -1300);
PAINT MONO (1650 -1300);
DISPLAY INVISIBLE (1650 -1300);
FORCEPROP 0 LAST CDS_SEC 1
J 0
(1650 -1300);
DISPLAY 1.021277 (1650 -1300);
DISPLAY INVISIBLE (1650 -1300);
FORCEPROP 1 LASTPIN (1400 -1375) $PN 1
J 0
(1412 -1363);
DISPLAY 0.787234 (1412 -1363);
PAINT MONO (1412 -1363);
FORCEPROP 1 LASTPIN (1600 -1375) $PN 2
J 0
(1562 -1363);
DISPLAY 0.787234 (1562 -1363);
PAINT MONO (1562 -1363);
FORCEPROP 1 LAST PART_NUMBER CS00002JB13
J 0
(1175 -1425);
DISPLAY 0.723404 (1175 -1425);
PAINT WHITE (1175 -1425);
FORCEPROP 1 LAST WATTAGE 1/16W
J 2
(1375 -1475);
DISPLAY 0.723404 (1375 -1475);
PAINT SKYBLUE (1375 -1475);
FORCEPROP 1 LAST VALUE 0
J 2
(1650 -1350);
DISPLAY 0.723404 (1650 -1350);
PAINT SKYBLUE (1650 -1350);
FORCEPROP 1 LAST TOLERANCE 5%
J 0
(1625 -1425);
DISPLAY 0.723404 (1625 -1425);
PAINT SKYBLUE (1625 -1425);
FORCEPROP 1 LAST MATERIAL CHIP
J 0
(1675 -1475);
DISPLAY 0.723404 (1675 -1475);
PAINT SKYBLUE (1675 -1475);
FORCEPROP 1 LAST PACK_TYPE 0402LF
J 0
(1425 -1475);
DISPLAY 0.723404 (1425 -1475);
PAINT SKYBLUE (1425 -1475);
FORCEPROP 2 LAST CDS_LIB pure_quanta
J 0
(1500 -1375);
DISPLAY INVISIBLE (1500 -1375);
FORCEPROP 1 LAST PATH I39
J 0
(1450 -1225);
DISPLAY 0.978723 (1450 -1225);
PAINT WHITE (1450 -1225);
DISPLAY INVISIBLE (1450 -1225);
FORCEADD Q_CAP..1
(-3575 -1300);
FORCEPROP 1 LAST LOCATION PC2223
J 0
(-3500 -1150);
DISPLAY 0.723404 (-3500 -1150);
PAINT AQUA (-3500 -1150);
FORCEPROP 0 LAST $SEC 1
J 0
(-3500 -1100);
DISPLAY 0.680851 (-3500 -1100);
PAINT MONO (-3500 -1100);
DISPLAY INVISIBLE (-3500 -1100);
FORCEPROP 0 LAST CDS_SEC 1
J 0
(-3500 -1100);
DISPLAY 1.021277 (-3500 -1100);
DISPLAY INVISIBLE (-3500 -1100);
FORCEPROP 1 LASTPIN (-3575 -1200) $PN 1
J 0
(-3565 -1220);
DISPLAY 0.787234 (-3565 -1220);
PAINT MONO (-3565 -1220);
FORCEPROP 1 LASTPIN (-3575 -1400) $PN 2
J 0
(-3565 -1420);
DISPLAY 0.787234 (-3565 -1420);
PAINT MONO (-3565 -1420);
FORCEPROP 1 LAST MATERIAL X6S
J 0
(-3500 -1300);
DISPLAY 0.723404 (-3500 -1300);
PAINT SKYBLUE (-3500 -1300);
FORCEPROP 1 LAST VOLTAGE 25V
J 0
(-3500 -1250);
DISPLAY 0.723404 (-3500 -1250);
PAINT SKYBLUE (-3500 -1250);
FORCEPROP 1 LAST VALUE 1UF
J 0
(-3500 -1200);
DISPLAY 0.723404 (-3500 -1200);
PAINT SKYBLUE (-3500 -1200);
FORCEPROP 1 LAST PART_NUMBER CH5104KEB02
J 0
(-3500 -1350);
DISPLAY 0.723404 (-3500 -1350);
PAINT WHITE (-3500 -1350);
FORCEPROP 1 LAST PACK_TYPE C0402
J 0
(-3500 -1400);
DISPLAY 0.723404 (-3500 -1400);
PAINT SKYBLUE (-3500 -1400);
FORCEPROP 1 LAST TOLERANCE 10%
J 0
(-3525 -1350);
DISPLAY 0.978723 (-3525 -1350);
PAINT SKYBLUE (-3525 -1350);
DISPLAY INVISIBLE (-3525 -1350);
FORCEPROP 2 LAST CDS_LIB pure_quanta
J 0
(-3575 -1300);
DISPLAY INVISIBLE (-3575 -1300);
FORCEPROP 1 LAST PATH I4
J 0
(-3525 -1150);
DISPLAY 0.978723 (-3525 -1150);
PAINT WHITE (-3525 -1150);
DISPLAY INVISIBLE (-3525 -1150);
FORCEADD Q_RES..1
(1500 -1200);
FORCEPROP 1 LAST LOCATION PR3994
J 0
(1200 -1200);
DISPLAY 0.723404 (1200 -1200);
PAINT AQUA (1200 -1200);
FORCEPROP 0 LAST $SEC 1
J 0
(1650 -1125);
DISPLAY 0.680851 (1650 -1125);
PAINT MONO (1650 -1125);
DISPLAY INVISIBLE (1650 -1125);
FORCEPROP 0 LAST CDS_SEC 1
J 0
(1650 -1125);
DISPLAY 1.021277 (1650 -1125);
DISPLAY INVISIBLE (1650 -1125);
FORCEPROP 1 LASTPIN (1400 -1200) $PN 1
J 0
(1412 -1188);
DISPLAY 0.787234 (1412 -1188);
PAINT MONO (1412 -1188);
FORCEPROP 1 LASTPIN (1600 -1200) $PN 2
J 0
(1562 -1188);
DISPLAY 0.787234 (1562 -1188);
PAINT MONO (1562 -1188);
FORCEPROP 1 LAST PART_NUMBER CS00002JB13
J 0
(1175 -1250);
DISPLAY 0.723404 (1175 -1250);
PAINT WHITE (1175 -1250);
FORCEPROP 1 LAST WATTAGE 1/16W
J 2
(1375 -1300);
DISPLAY 0.723404 (1375 -1300);
PAINT SKYBLUE (1375 -1300);
FORCEPROP 1 LAST PACK_TYPE 0402LF
J 0
(1425 -1300);
DISPLAY 0.723404 (1425 -1300);
PAINT SKYBLUE (1425 -1300);
FORCEPROP 1 LAST MATERIAL CHIP
J 0
(1675 -1300);
DISPLAY 0.723404 (1675 -1300);
PAINT SKYBLUE (1675 -1300);
FORCEPROP 1 LAST TOLERANCE 5%
J 0
(1625 -1250);
DISPLAY 0.723404 (1625 -1250);
PAINT SKYBLUE (1625 -1250);
FORCEPROP 1 LAST VALUE 0
J 2
(1650 -1175);
DISPLAY 0.723404 (1650 -1175);
PAINT SKYBLUE (1650 -1175);
FORCEPROP 2 LAST CDS_LIB pure_quanta
J 0
(1500 -1200);
DISPLAY INVISIBLE (1500 -1200);
FORCEPROP 1 LAST PATH I40
J 0
(1450 -1050);
DISPLAY 0.978723 (1450 -1050);
PAINT WHITE (1450 -1050);
DISPLAY INVISIBLE (1450 -1050);
FORCEADD UNIVERSAL_POWER..1
(1125 -325);
FORCEPROP 3 LASTPIN (1125 -375) SIG_NAME P12V_AUX\g
J 0
(1135 -365);
DISPLAY 0.659574 (1135 -365);
PAINT MONO (1135 -365);
DISPLAY INVISIBLE (1135 -365);
FORCEPROP 1 LAST HDL_POWER P12V_AUX
J 1
(1125 -275);
DISPLAY 0.723404 (1125 -275);
PAINT GREEN (1125 -275);
FORCEPROP 2 LAST ROOM AUX_SW
J 0
(1125 -225);
DISPLAY 0.617021 (1125 -225);
FORCEPROP 2 LAST BOM_COST MIO_VRD_SB
J 0
(1125 -225);
DISPLAY 0.617021 (1125 -225);
PAINT PURPLE (1125 -225);
DISPLAY INVISIBLE (1125 -225);
FORCEPROP 2 LAST CDS_LIB pure_quanta_power
J 0
(1125 -325);
DISPLAY INVISIBLE (1125 -325);
FORCEPROP 1 LAST PATH I41
J 0
(1175 -300);
DISPLAY 0.872340 (1175 -300);
PAINT AQUA (1175 -300);
DISPLAY INVISIBLE (1175 -300);
FORCEADD OFFPAGE..4
(2275 -1775);
FORCEPROP 2 LAST $XR2 303 
J 0
(2701 -1775);
DISPLAY 0.638298 (2701 -1775);
PAINT MONO (2701 -1775);
FORCEPROP 2 LAST $XR1 302 
J 0
(2581 -1775);
DISPLAY 0.638298 (2581 -1775);
PAINT MONO (2581 -1775);
FORCEPROP 2 LAST $XR0 301 
J 0
(2461 -1775);
DISPLAY 0.638298 (2461 -1775);
PAINT MONO (2461 -1775);
FORCEPROP 2 LAST CDS_LIB standard
J 0
(2275 -1775);
DISPLAY INVISIBLE (2275 -1775);
FORCEPROP 1 LAST OFFPAGE TRUE
J 0
(2600 -1900);
DISPLAY 0.872340 (2600 -1900);
PAINT GREEN (2600 -1900);
DISPLAY INVISIBLE (2600 -1900);
FORCEPROP 1 LAST COMMENT_BODY TRUE
J 0
(2250 -1875);
DISPLAY 0.872340 (2250 -1875);
PAINT GREEN (2250 -1875);
DISPLAY INVISIBLE (2250 -1875);
FORCEPROP 2 LAST PATH I42
J 0
(2725 -1725);
DISPLAY 1.021277 (2725 -1725);
DISPLAY INVISIBLE (2725 -1725);
FORCEADD OFFPAGE..5
R 2
(2275 -1575);
FORCEPROP 2 LAST $XR2 301 
J 0
(2704 -1575);
DISPLAY 0.638298 (2704 -1575);
PAINT MONO (2704 -1575);
FORCEPROP 2 LAST $XR1 303 
J 0
(2584 -1575);
DISPLAY 0.638298 (2584 -1575);
PAINT MONO (2584 -1575);
FORCEPROP 2 LAST $XR0 302 
J 0
(2464 -1575);
DISPLAY 0.638298 (2464 -1575);
PAINT MONO (2464 -1575);
FORCEPROP 2 LAST CDS_LIB standard
J 2
(2275 -1575);
DISPLAY INVISIBLE (2275 -1575);
FORCEPROP 1 LAST OFFPAGE TRUE
J 2
(1950 -1700);
DISPLAY 0.872340 (1950 -1700);
PAINT AQUA (1950 -1700);
DISPLAY INVISIBLE (1950 -1700);
FORCEPROP 1 LAST COMMENT_BODY TRUE
J 2
(2175 -1650);
DISPLAY 1.170213 (2175 -1650);
PAINT GREEN (2175 -1650);
DISPLAY INVISIBLE (2175 -1650);
FORCEPROP 2 LAST PATH I43
J 0
(2725 -1525);
DISPLAY 1.021277 (2725 -1525);
DISPLAY INVISIBLE (2725 -1525);
FORCEADD OFFPAGE..5
R 2
(2275 -1675);
FORCEPROP 2 LAST $XR2 301 
J 0
(2704 -1675);
DISPLAY 0.638298 (2704 -1675);
PAINT MONO (2704 -1675);
FORCEPROP 2 LAST $XR1 303 
J 0
(2584 -1675);
DISPLAY 0.638298 (2584 -1675);
PAINT MONO (2584 -1675);
FORCEPROP 2 LAST $XR0 302 
J 0
(2464 -1675);
DISPLAY 0.638298 (2464 -1675);
PAINT MONO (2464 -1675);
FORCEPROP 2 LAST CDS_LIB standard
J 2
(2275 -1675);
DISPLAY INVISIBLE (2275 -1675);
FORCEPROP 1 LAST OFFPAGE TRUE
J 2
(1950 -1800);
DISPLAY 0.872340 (1950 -1800);
PAINT AQUA (1950 -1800);
DISPLAY INVISIBLE (1950 -1800);
FORCEPROP 1 LAST COMMENT_BODY TRUE
J 2
(2175 -1750);
DISPLAY 1.170213 (2175 -1750);
PAINT GREEN (2175 -1750);
DISPLAY INVISIBLE (2175 -1750);
FORCEPROP 2 LAST PATH I44
J 0
(2725 -1625);
DISPLAY 1.021277 (2725 -1625);
DISPLAY INVISIBLE (2725 -1625);
FORCEADD OFFPAGE..4
(2275 -1375);
FORCEPROP 2 LAST $XR2 303 
J 0
(2701 -1375);
DISPLAY 0.638298 (2701 -1375);
PAINT MONO (2701 -1375);
FORCEPROP 2 LAST $XR1 302 
J 0
(2581 -1375);
DISPLAY 0.638298 (2581 -1375);
PAINT MONO (2581 -1375);
FORCEPROP 2 LAST $XR0 301 
J 0
(2461 -1375);
DISPLAY 0.638298 (2461 -1375);
PAINT MONO (2461 -1375);
FORCEPROP 2 LAST CDS_LIB standard
J 0
(2275 -1375);
DISPLAY INVISIBLE (2275 -1375);
FORCEPROP 1 LAST OFFPAGE TRUE
J 0
(2600 -1500);
DISPLAY 0.872340 (2600 -1500);
PAINT GREEN (2600 -1500);
DISPLAY INVISIBLE (2600 -1500);
FORCEPROP 1 LAST COMMENT_BODY TRUE
J 0
(2250 -1475);
DISPLAY 0.872340 (2250 -1475);
PAINT GREEN (2250 -1475);
DISPLAY INVISIBLE (2250 -1475);
FORCEPROP 2 LAST PATH I45
J 0
(2725 -1325);
DISPLAY 1.021277 (2725 -1325);
DISPLAY INVISIBLE (2725 -1325);
FORCEADD OFFPAGE..5
R 2
(2275 -1200);
FORCEPROP 2 LAST $XR2 301 
J 0
(2704 -1200);
DISPLAY 0.638298 (2704 -1200);
PAINT MONO (2704 -1200);
FORCEPROP 2 LAST $XR1 303 
J 0
(2584 -1200);
DISPLAY 0.638298 (2584 -1200);
PAINT MONO (2584 -1200);
FORCEPROP 2 LAST $XR0 302 
J 0
(2464 -1200);
DISPLAY 0.638298 (2464 -1200);
PAINT MONO (2464 -1200);
FORCEPROP 2 LAST CDS_LIB standard
J 0
(2275 -1200);
DISPLAY INVISIBLE (2275 -1200);
FORCEPROP 1 LAST OFFPAGE TRUE
J 2
(1950 -1325);
DISPLAY 0.872340 (1950 -1325);
PAINT AQUA (1950 -1325);
DISPLAY INVISIBLE (1950 -1325);
FORCEPROP 1 LAST COMMENT_BODY TRUE
J 2
(2175 -1275);
DISPLAY 1.170213 (2175 -1275);
PAINT GREEN (2175 -1275);
DISPLAY INVISIBLE (2175 -1275);
FORCEPROP 2 LAST PATH I46
J 0
(2725 -1150);
DISPLAY 1.021277 (2725 -1150);
DISPLAY INVISIBLE (2725 -1150);
FORCEADD Q_CAP..1
(1000 850);
FORCEPROP 1 LAST LOCATION PC2226
J 0
(1050 925);
DISPLAY 0.723404 (1050 925);
PAINT AQUA (1050 925);
FORCEPROP 0 LAST $SEC 1
J 0
(1050 975);
DISPLAY 0.680851 (1050 975);
PAINT MONO (1050 975);
DISPLAY INVISIBLE (1050 975);
FORCEPROP 0 LAST CDS_SEC 1
J 0
(1050 975);
DISPLAY 1.021277 (1050 975);
DISPLAY INVISIBLE (1050 975);
FORCEPROP 1 LASTPIN (1000 950) $PN 1
J 0
(1010 930);
DISPLAY 0.787234 (1010 930);
PAINT MONO (1010 930);
FORCEPROP 1 LASTPIN (1000 750) $PN 2
J 0
(1010 730);
DISPLAY 0.787234 (1010 730);
PAINT MONO (1010 730);
FORCEPROP 1 LAST MATERIAL X7R
J 0
(1050 775);
DISPLAY 0.723404 (1050 775);
PAINT SKYBLUE (1050 775);
FORCEPROP 1 LAST PART_NUMBER CH3683K1B09
J 0
(1050 725);
DISPLAY 0.723404 (1050 725);
PAINT WHITE (1050 725);
FORCEPROP 1 LAST PACK_TYPE 0402
J 0
(1050 675);
DISPLAY 0.723404 (1050 675);
PAINT SKYBLUE (1050 675);
FORCEPROP 1 LAST VALUE 0.068UF
J 0
(1050 875);
DISPLAY 0.723404 (1050 875);
PAINT SKYBLUE (1050 875);
FORCEPROP 1 LAST VOLTAGE 16V
J 0
(1050 825);
DISPLAY 0.723404 (1050 825);
PAINT SKYBLUE (1050 825);
FORCEPROP 2 LAST CDS_LIB pure_quanta
J 0
(1000 850);
DISPLAY INVISIBLE (1000 850);
FORCEPROP 1 LAST TOLERANCE 10%
J 0
(1050 800);
DISPLAY 0.978723 (1050 800);
PAINT SKYBLUE (1050 800);
DISPLAY INVISIBLE (1050 800);
FORCEPROP 1 LAST PATH I47
J 0
(1050 1000);
DISPLAY 0.978723 (1050 1000);
PAINT WHITE (1050 1000);
DISPLAY INVISIBLE (1050 1000);
FORCEADD UNIVERSAL_GND..1
(1000 625);
FORCEPROP 3 LASTPIN (1000 675) SIG_NAME AGND_HSC\g
J 0
(1010 685);
DISPLAY 0.659574 (1010 685);
PAINT MONO (1010 685);
DISPLAY INVISIBLE (1010 685);
FORCEPROP 1 LAST HDL_POWER AGND_HSC
J 1
(1025 550);
DISPLAY 0.723404 (1025 550);
PAINT GREEN (1025 550);
FORCEPROP 2 LAST CDS_LIB pure_quanta_power
J 0
(1000 625);
DISPLAY INVISIBLE (1000 625);
FORCEPROP 1 LAST PATH I48
J 0
(1075 625);
DISPLAY 0.872340 (1075 625);
PAINT AQUA (1075 625);
DISPLAY INVISIBLE (1075 625);
FORCEADD Q_RES..1
(1500 1400);
FORCEPROP 1 LAST LOCATION PR3993
J 0
(1200 1400);
DISPLAY 0.723404 (1200 1400);
PAINT AQUA (1200 1400);
FORCEPROP 0 LAST $SEC 1
J 0
(1650 1475);
DISPLAY 0.680851 (1650 1475);
PAINT MONO (1650 1475);
DISPLAY INVISIBLE (1650 1475);
FORCEPROP 0 LAST CDS_SEC 1
J 0
(1650 1475);
DISPLAY 1.021277 (1650 1475);
DISPLAY INVISIBLE (1650 1475);
FORCEPROP 1 LASTPIN (1400 1400) $PN 1
J 0
(1412 1412);
DISPLAY 0.787234 (1412 1412);
PAINT MONO (1412 1412);
FORCEPROP 1 LASTPIN (1600 1400) $PN 2
J 0
(1562 1412);
DISPLAY 0.787234 (1562 1412);
PAINT MONO (1562 1412);
FORCEPROP 1 LAST PART_NUMBER CS00002JB13
J 0
(1175 1350);
DISPLAY 0.723404 (1175 1350);
PAINT WHITE (1175 1350);
FORCEPROP 1 LAST PACK_TYPE 0402LF
J 0
(1425 1300);
DISPLAY 0.723404 (1425 1300);
PAINT SKYBLUE (1425 1300);
FORCEPROP 1 LAST VALUE 0
J 2
(1650 1425);
DISPLAY 0.723404 (1650 1425);
PAINT SKYBLUE (1650 1425);
FORCEPROP 1 LAST MATERIAL CHIP
J 0
(1675 1300);
DISPLAY 0.723404 (1675 1300);
PAINT SKYBLUE (1675 1300);
FORCEPROP 1 LAST TOLERANCE 5%
J 0
(1625 1350);
DISPLAY 0.723404 (1625 1350);
PAINT SKYBLUE (1625 1350);
FORCEPROP 1 LAST WATTAGE 1/16W
J 2
(1375 1300);
DISPLAY 0.723404 (1375 1300);
PAINT SKYBLUE (1375 1300);
FORCEPROP 2 LAST CDS_LIB pure_quanta
J 0
(1500 1400);
DISPLAY INVISIBLE (1500 1400);
FORCEPROP 1 LAST PATH I49
J 0
(1450 1550);
DISPLAY 0.978723 (1450 1550);
PAINT WHITE (1450 1550);
DISPLAY INVISIBLE (1450 1550);
FORCEADD OFFPAGE..4
R 2
(-2900 -1425);
FORCEPROP 2 LAST $XR2 303 
J 0
(-3152 -1461);
DISPLAY 0.638298 (-3152 -1461);
PAINT MONO (-3152 -1461);
FORCEPROP 2 LAST $XR1 302 
J 0
(-3272 -1425);
DISPLAY 0.638298 (-3272 -1425);
PAINT MONO (-3272 -1425);
FORCEPROP 2 LAST $XR0 301 
J 0
(-3152 -1425);
DISPLAY 0.638298 (-3152 -1425);
PAINT MONO (-3152 -1425);
FORCEPROP 2 LAST CDS_LIB standard
J 0
(-2900 -1425);
DISPLAY INVISIBLE (-2900 -1425);
FORCEPROP 1 LAST OFFPAGE TRUE
J 2
(-3225 -1550);
DISPLAY 0.872340 (-3225 -1550);
PAINT GREEN (-3225 -1550);
DISPLAY INVISIBLE (-3225 -1550);
FORCEPROP 1 LAST COMMENT_BODY TRUE
J 2
(-2875 -1525);
DISPLAY 0.872340 (-2875 -1525);
PAINT GREEN (-2875 -1525);
DISPLAY INVISIBLE (-2875 -1525);
FORCEPROP 2 LAST PATH I5
J 0
(-3150 -1375);
DISPLAY 1.021277 (-3150 -1375);
DISPLAY INVISIBLE (-3150 -1375);
FORCEADD Q_RES..1
(1500 1575);
FORCEPROP 1 LAST LOCATION PR3992
J 0
(1200 1575);
DISPLAY 0.723404 (1200 1575);
PAINT AQUA (1200 1575);
FORCEPROP 0 LAST $SEC 1
J 0
(1650 1650);
DISPLAY 0.680851 (1650 1650);
PAINT MONO (1650 1650);
DISPLAY INVISIBLE (1650 1650);
FORCEPROP 0 LAST CDS_SEC 1
J 0
(1650 1650);
DISPLAY 1.021277 (1650 1650);
DISPLAY INVISIBLE (1650 1650);
FORCEPROP 1 LASTPIN (1400 1575) $PN 1
J 0
(1412 1587);
DISPLAY 0.787234 (1412 1587);
PAINT MONO (1412 1587);
FORCEPROP 1 LASTPIN (1600 1575) $PN 2
J 0
(1562 1587);
DISPLAY 0.787234 (1562 1587);
PAINT MONO (1562 1587);
FORCEPROP 1 LAST WATTAGE 1/16W
J 2
(1375 1475);
DISPLAY 0.723404 (1375 1475);
PAINT SKYBLUE (1375 1475);
FORCEPROP 1 LAST PART_NUMBER CS00002JB13
J 0
(1175 1525);
DISPLAY 0.723404 (1175 1525);
PAINT WHITE (1175 1525);
FORCEPROP 1 LAST TOLERANCE 5%
J 0
(1625 1525);
DISPLAY 0.723404 (1625 1525);
PAINT SKYBLUE (1625 1525);
FORCEPROP 1 LAST MATERIAL CHIP
J 0
(1675 1475);
DISPLAY 0.723404 (1675 1475);
PAINT SKYBLUE (1675 1475);
FORCEPROP 1 LAST PACK_TYPE 0402LF
J 0
(1425 1475);
DISPLAY 0.723404 (1425 1475);
PAINT SKYBLUE (1425 1475);
FORCEPROP 1 LAST VALUE 0
J 2
(1650 1600);
DISPLAY 0.723404 (1650 1600);
PAINT SKYBLUE (1650 1600);
FORCEPROP 2 LAST CDS_LIB pure_quanta
J 0
(1500 1575);
DISPLAY INVISIBLE (1500 1575);
FORCEPROP 1 LAST PATH I50
J 0
(1450 1725);
DISPLAY 0.978723 (1450 1725);
PAINT WHITE (1450 1725);
DISPLAY INVISIBLE (1450 1725);
FORCEADD UNIVERSAL_POWER..1
(1125 2450);
FORCEPROP 3 LASTPIN (1125 2400) SIG_NAME P12V_AUX\g
J 0
(1135 2410);
DISPLAY 0.659574 (1135 2410);
PAINT MONO (1135 2410);
DISPLAY INVISIBLE (1135 2410);
FORCEPROP 1 LAST HDL_POWER P12V_AUX
J 1
(1125 2500);
DISPLAY 0.723404 (1125 2500);
PAINT GREEN (1125 2500);
FORCEPROP 2 LAST ROOM AUX_SW
J 0
(1125 2550);
DISPLAY 0.617021 (1125 2550);
FORCEPROP 2 LAST BOM_COST MIO_VRD_SB
J 0
(1125 2550);
DISPLAY 0.617021 (1125 2550);
PAINT PURPLE (1125 2550);
DISPLAY INVISIBLE (1125 2550);
FORCEPROP 2 LAST CDS_LIB pure_quanta_power
J 0
(1125 2450);
DISPLAY INVISIBLE (1125 2450);
FORCEPROP 1 LAST PATH I51
J 0
(1175 2475);
DISPLAY 0.872340 (1175 2475);
PAINT AQUA (1175 2475);
DISPLAY INVISIBLE (1175 2475);
FORCEADD OFFPAGE..4
(2300 1000);
FORCEPROP 2 LAST $XR2 303 
J 0
(2726 1000);
DISPLAY 0.638298 (2726 1000);
PAINT MONO (2726 1000);
FORCEPROP 2 LAST $XR1 302 
J 0
(2606 1000);
DISPLAY 0.638298 (2606 1000);
PAINT MONO (2606 1000);
FORCEPROP 2 LAST $XR0 301 
J 0
(2486 1000);
DISPLAY 0.638298 (2486 1000);
PAINT MONO (2486 1000);
FORCEPROP 2 LAST CDS_LIB standard
J 0
(2300 1000);
DISPLAY INVISIBLE (2300 1000);
FORCEPROP 1 LAST OFFPAGE TRUE
J 0
(2625 875);
DISPLAY 0.872340 (2625 875);
PAINT GREEN (2625 875);
DISPLAY INVISIBLE (2625 875);
FORCEPROP 1 LAST COMMENT_BODY TRUE
J 0
(2275 900);
DISPLAY 0.872340 (2275 900);
PAINT GREEN (2275 900);
DISPLAY INVISIBLE (2275 900);
FORCEPROP 2 LAST PATH I52
J 0
(2750 1050);
DISPLAY 1.021277 (2750 1050);
DISPLAY INVISIBLE (2750 1050);
FORCEADD OFFPAGE..5
R 2
(2300 1100);
FORCEPROP 2 LAST $XR2 301 
J 0
(2729 1100);
DISPLAY 0.638298 (2729 1100);
PAINT MONO (2729 1100);
FORCEPROP 2 LAST $XR1 303 
J 0
(2609 1100);
DISPLAY 0.638298 (2609 1100);
PAINT MONO (2609 1100);
FORCEPROP 2 LAST $XR0 302 
J 0
(2489 1100);
DISPLAY 0.638298 (2489 1100);
PAINT MONO (2489 1100);
FORCEPROP 2 LAST CDS_LIB standard
J 2
(2300 1100);
DISPLAY INVISIBLE (2300 1100);
FORCEPROP 1 LAST OFFPAGE TRUE
J 2
(1975 975);
DISPLAY 0.872340 (1975 975);
PAINT AQUA (1975 975);
DISPLAY INVISIBLE (1975 975);
FORCEPROP 1 LAST COMMENT_BODY TRUE
J 2
(2200 1025);
DISPLAY 1.170213 (2200 1025);
PAINT GREEN (2200 1025);
DISPLAY INVISIBLE (2200 1025);
FORCEPROP 2 LAST PATH I53
J 0
(2750 1150);
DISPLAY 1.021277 (2750 1150);
DISPLAY INVISIBLE (2750 1150);
FORCEADD OFFPAGE..5
R 2
(2300 1200);
FORCEPROP 2 LAST $XR2 301 
J 0
(2729 1200);
DISPLAY 0.638298 (2729 1200);
PAINT MONO (2729 1200);
FORCEPROP 2 LAST $XR1 303 
J 0
(2609 1200);
DISPLAY 0.638298 (2609 1200);
PAINT MONO (2609 1200);
FORCEPROP 2 LAST $XR0 302 
J 0
(2489 1200);
DISPLAY 0.638298 (2489 1200);
PAINT MONO (2489 1200);
FORCEPROP 2 LAST CDS_LIB standard
J 2
(2300 1200);
DISPLAY INVISIBLE (2300 1200);
FORCEPROP 1 LAST OFFPAGE TRUE
J 2
(1975 1075);
DISPLAY 0.872340 (1975 1075);
PAINT AQUA (1975 1075);
DISPLAY INVISIBLE (1975 1075);
FORCEPROP 1 LAST COMMENT_BODY TRUE
J 2
(2200 1125);
DISPLAY 1.170213 (2200 1125);
PAINT GREEN (2200 1125);
DISPLAY INVISIBLE (2200 1125);
FORCEPROP 2 LAST PATH I54
J 0
(2750 1250);
DISPLAY 1.021277 (2750 1250);
DISPLAY INVISIBLE (2750 1250);
FORCEADD OFFPAGE..4
(2300 1400);
FORCEPROP 2 LAST $XR2 303 
J 0
(2726 1400);
DISPLAY 0.638298 (2726 1400);
PAINT MONO (2726 1400);
FORCEPROP 2 LAST $XR1 302 
J 0
(2606 1400);
DISPLAY 0.638298 (2606 1400);
PAINT MONO (2606 1400);
FORCEPROP 2 LAST $XR0 301 
J 0
(2486 1400);
DISPLAY 0.638298 (2486 1400);
PAINT MONO (2486 1400);
FORCEPROP 2 LAST CDS_LIB standard
J 0
(2300 1400);
DISPLAY INVISIBLE (2300 1400);
FORCEPROP 1 LAST OFFPAGE TRUE
J 0
(2625 1275);
DISPLAY 0.872340 (2625 1275);
PAINT GREEN (2625 1275);
DISPLAY INVISIBLE (2625 1275);
FORCEPROP 1 LAST COMMENT_BODY TRUE
J 0
(2275 1300);
DISPLAY 0.872340 (2275 1300);
PAINT GREEN (2275 1300);
DISPLAY INVISIBLE (2275 1300);
FORCEPROP 2 LAST PATH I55
J 0
(2750 1450);
DISPLAY 1.021277 (2750 1450);
DISPLAY INVISIBLE (2750 1450);
FORCEADD OFFPAGE..5
R 2
(2300 1575);
FORCEPROP 2 LAST $XR2 301 
J 0
(2729 1575);
DISPLAY 0.638298 (2729 1575);
PAINT MONO (2729 1575);
FORCEPROP 2 LAST $XR1 303 
J 0
(2609 1575);
DISPLAY 0.638298 (2609 1575);
PAINT MONO (2609 1575);
FORCEPROP 2 LAST $XR0 302 
J 0
(2489 1575);
DISPLAY 0.638298 (2489 1575);
PAINT MONO (2489 1575);
FORCEPROP 2 LAST CDS_LIB standard
J 0
(2300 1575);
DISPLAY INVISIBLE (2300 1575);
FORCEPROP 1 LAST OFFPAGE TRUE
J 2
(1975 1450);
DISPLAY 0.872340 (1975 1450);
PAINT AQUA (1975 1450);
DISPLAY INVISIBLE (1975 1450);
FORCEPROP 1 LAST COMMENT_BODY TRUE
J 2
(2200 1500);
DISPLAY 1.170213 (2200 1500);
PAINT GREEN (2200 1500);
DISPLAY INVISIBLE (2200 1500);
FORCEPROP 2 LAST PATH I56
J 0
(2750 1625);
DISPLAY 1.021277 (2750 1625);
DISPLAY INVISIBLE (2750 1625);
FORCEADD Q_RES..1
R 1
(-3575 -825);
FORCEPROP 1 LAST LOCATION PR3981
J 0
(-3500 -675);
DISPLAY 0.723404 (-3500 -675);
PAINT AQUA (-3500 -675);
FORCEPROP 0 LAST $SEC 1
R 1
J 0
(-3500 -625);
DISPLAY 0.680851 (-3500 -625);
PAINT MONO (-3500 -625);
DISPLAY INVISIBLE (-3500 -625);
FORCEPROP 0 LAST CDS_SEC 1
R 1
J 0
(-3500 -625);
DISPLAY 1.021277 (-3500 -625);
DISPLAY INVISIBLE (-3500 -625);
FORCEPROP 1 LASTPIN (-3575 -925) $PN 1
R 1
J 0
(-3587 -913);
DISPLAY 0.787234 (-3587 -913);
PAINT MONO (-3587 -913);
FORCEPROP 1 LASTPIN (-3575 -725) $PN 2
R 1
J 0
(-3587 -763);
DISPLAY 0.787234 (-3587 -763);
PAINT MONO (-3587 -763);
FORCEPROP 1 LAST MATERIAL CHIP
J 0
(-3500 -825);
DISPLAY 0.787234 (-3500 -825);
PAINT SKYBLUE (-3500 -825);
FORCEPROP 1 LAST TOLERANCE 5%
J 0
(-3500 -775);
DISPLAY 0.723404 (-3500 -775);
PAINT SKYBLUE (-3500 -775);
FORCEPROP 1 LAST WATTAGE 1/16W
J 0
(-3500 -875);
DISPLAY 0.723404 (-3500 -875);
PAINT SKYBLUE (-3500 -875);
FORCEPROP 1 LAST PART_NUMBER CS00002JB13
J 0
(-3500 -925);
DISPLAY 0.723404 (-3500 -925);
PAINT WHITE (-3500 -925);
FORCEPROP 1 LAST PACK_TYPE 0402LF
J 0
(-3500 -975);
DISPLAY 0.723404 (-3500 -975);
PAINT SKYBLUE (-3500 -975);
FORCEPROP 1 LAST VALUE 0
R 2
J 0
(-3475 -700);
DISPLAY 0.723404 (-3475 -700);
PAINT SKYBLUE (-3475 -700);
FORCEPROP 2 LAST CDS_LIB pure_quanta
J 0
(-3575 -825);
DISPLAY INVISIBLE (-3575 -825);
FORCEPROP 1 LAST PATH I6
R 1
J 0
(-3725 -875);
DISPLAY 0.978723 (-3725 -875);
PAINT WHITE (-3725 -875);
DISPLAY INVISIBLE (-3725 -875);
FORCEADD UNIVERSAL_POWER..1
(-3575 -575);
FORCEPROP 3 LASTPIN (-3575 -625) SIG_NAME HSC_VDD\g
J 0
(-3565 -615);
DISPLAY 0.659574 (-3565 -615);
PAINT MONO (-3565 -615);
DISPLAY INVISIBLE (-3565 -615);
FORCEPROP 1 LAST HDL_POWER HSC_VDD
J 1
(-3575 -525);
DISPLAY 0.723404 (-3575 -525);
PAINT GREEN (-3575 -525);
FORCEPROP 2 LAST ROOM AUX_SW
J 0
(-3575 -475);
DISPLAY 0.617021 (-3575 -475);
FORCEPROP 2 LAST BOM_COST MIO_VRD_SB
J 0
(-3575 -475);
DISPLAY 0.617021 (-3575 -475);
PAINT PURPLE (-3575 -475);
DISPLAY INVISIBLE (-3575 -475);
FORCEPROP 2 LAST CDS_LIB pure_quanta_power
J 0
(-3575 -575);
DISPLAY INVISIBLE (-3575 -575);
FORCEPROP 1 LAST PATH I7
J 0
(-3525 -550);
DISPLAY 0.872340 (-3525 -550);
PAINT AQUA (-3525 -550);
DISPLAY INVISIBLE (-3525 -550);
FORCEADD UNIVERSAL_GND..1
(-2700 -1225);
FORCEPROP 3 LASTPIN (-2700 -1175) SIG_NAME AGND_HSC\g
J 0
(-2690 -1165);
DISPLAY 0.659574 (-2690 -1165);
PAINT MONO (-2690 -1165);
DISPLAY INVISIBLE (-2690 -1165);
FORCEPROP 1 LAST HDL_POWER AGND_HSC
J 1
(-2675 -1300);
DISPLAY 0.723404 (-2675 -1300);
PAINT GREEN (-2675 -1300);
FORCEPROP 2 LAST CDS_LIB pure_quanta_power
J 0
(-2700 -1225);
DISPLAY INVISIBLE (-2700 -1225);
FORCEPROP 1 LAST PATH I8
J 0
(-2625 -1225);
DISPLAY 0.872340 (-2625 -1225);
PAINT AQUA (-2625 -1225);
DISPLAY INVISIBLE (-2625 -1225);
FORCEADD OFFPAGE..4
R 2
(-2075 -1525);
FORCEPROP 2 LAST $XR2 303 
J 0
(-2597 -1525);
DISPLAY 0.638298 (-2597 -1525);
PAINT MONO (-2597 -1525);
FORCEPROP 2 LAST $XR1 302 
J 0
(-2477 -1525);
DISPLAY 0.638298 (-2477 -1525);
PAINT MONO (-2477 -1525);
FORCEPROP 2 LAST $XR0 301 
J 0
(-2357 -1525);
DISPLAY 0.638298 (-2357 -1525);
PAINT MONO (-2357 -1525);
FORCEPROP 2 LAST CDS_LIB standard
J 0
(-2075 -1525);
DISPLAY INVISIBLE (-2075 -1525);
FORCEPROP 1 LAST OFFPAGE TRUE
J 2
(-2400 -1650);
DISPLAY 0.872340 (-2400 -1650);
PAINT GREEN (-2400 -1650);
DISPLAY INVISIBLE (-2400 -1650);
FORCEPROP 1 LAST COMMENT_BODY TRUE
J 2
(-2050 -1625);
DISPLAY 0.872340 (-2050 -1625);
PAINT GREEN (-2050 -1625);
DISPLAY INVISIBLE (-2050 -1625);
FORCEPROP 2 LAST PATH I9
J 0
(-2350 -1475);
DISPLAY 1.021277 (-2350 -1475);
DISPLAY INVISIBLE (-2350 -1475);
FORCEADD DNS..2
(-1925 825);
PAINT RED (-1925 825);
FORCEPROP 2 LAST CDS_LIB mstr_misc
J 0
(-1925 825);
DISPLAY INVISIBLE (-1925 825);
FORCEPROP 1 LAST COMMENT_BODY TRUE
R 1
J 0
(-1850 600);
DISPLAY 0.872340 (-1850 600);
PAINT GREEN (-1850 600);
DISPLAY INVISIBLE (-1850 600);
FORCEADD DNS..2
(-2700 850);
PAINT RED (-2700 850);
FORCEPROP 2 LAST CDS_LIB mstr_misc
J 0
(-2700 850);
DISPLAY INVISIBLE (-2700 850);
FORCEPROP 1 LAST COMMENT_BODY TRUE
R 1
J 0
(-2625 625);
DISPLAY 0.872340 (-2625 625);
PAINT GREEN (-2625 625);
DISPLAY INVISIBLE (-2625 625);
FORCEADD DNS..2
(-1975 -1925);
PAINT RED (-1975 -1925);
FORCEPROP 2 LAST CDS_LIB mstr_misc
J 0
(-1975 -1925);
DISPLAY INVISIBLE (-1975 -1925);
FORCEPROP 1 LAST COMMENT_BODY TRUE
R 1
J 0
(-1900 -2150);
DISPLAY 0.872340 (-1900 -2150);
PAINT GREEN (-1900 -2150);
DISPLAY INVISIBLE (-1900 -2150);
FORCEADD DNS..2
(-2675 -1950);
PAINT RED (-2675 -1950);
FORCEPROP 2 LAST CDS_LIB mstr_misc
J 0
(-2675 -1950);
DISPLAY INVISIBLE (-2675 -1950);
FORCEPROP 1 LAST COMMENT_BODY TRUE
R 1
J 0
(-2600 -2175);
DISPLAY 0.872340 (-2600 -2175);
PAINT GREEN (-2600 -2175);
DISPLAY INVISIBLE (-2600 -2175);
FORCEADD QUANTA_TITLE_BLOCK_C..1
(4725 -3325);
FORCEPROP 0 LAST CDS_CON_LAST_MODIFIED Fri Mar 11 14:53:39 2022
J 0
(2840 -3310);
PAINT MONO (2840 -3310);
DISPLAY INVISIBLE (2840 -3310);
FORCEPROP 2 LAST CUSTOM_TXT_CDS <XR_PAGE_TITLE>
J 0
(-3165 1925);
DISPLAY 0.638298 (-3165 1925);
PAINT PINK (-3165 1925);
DISPLAY INVISIBLE (-3165 1925);
FORCEPROP 2 LAST CUSTOM_TXT_CDS <Q_REV>
J 0
(4541 -3222);
DISPLAY 1.212766 (4541 -3222);
FORCEPROP 2 LAST CUSTOM_TXT_CDS <CON_PAGE_NUM> OF <CON_TOTAL_PAGES>
J 0
(4279 -3307);
DISPLAY 0.978723 (4279 -3307);
FORCEPROP 2 LAST CUSTOM_TXT_CDS <Q_PROJ>
J 0
(2343 -3223);
DISPLAY 1.212766 (2343 -3223);
FORCEPROP 2 LAST CUSTOM_TXT_CDS <Q_NUMBER>
J 0
(3322 -3222);
DISPLAY 1.212766 (3322 -3222);
FORCEPROP 2 LAST CUSTOM_TXT_CDS <CON_LAST_MODIFIED>
J 0
(2840 -3310);
DISPLAY 0.978723 (2840 -3310);
FORCEPROP 1 LAST CUSTOM_TXT_CDS <NAME_2>
J 0
(1550 -3275);
FORCEPROP 1 LAST CUSTOM_TXT_CDS <NAME_1>
J 0
(1550 -3150);
FORCEPROP 1 LAST Q_DEPT BU9
J 1
(962 -3276);
DISPLAY 1.957447 (962 -3276);
PAINT GREEN (962 -3276);
FORCEPROP 1 LAST Q_TITLE HSC MP5990 (3/4)
J 0
(-4641 -3299);
DISPLAY 2.446809 (-4641 -3299);
PAINT GREEN (-4641 -3299);
FORCEPROP 1 LAST CDS_LMAN_SYM_OUTLINE -9475,6775,100,-125
J 0
(4725 -3325);
DISPLAY 0.468085 (4725 -3325);
PAINT GREEN (4725 -3325);
DISPLAY INVISIBLE (4725 -3325);
FORCEPROP 2 LAST CDS_LIB pure_quanta
J 0
(4725 -3325);
PAINT MONO (4725 -3325);
DISPLAY INVISIBLE (4725 -3325);
FORCEPROP 2 LAST PAGE_BORDER TRUE
J 0
(-3165 1925);
DISPLAY 0.638298 (-3165 1925);
PAINT PINK (-3165 1925);
DISPLAY INVISIBLE (-3165 1925);
FORCEPROP 1 LAST COMMENT_BODY TRUE
J 0
(4737 -3338);
DISPLAY 0.978723 (4737 -3338);
PAINT GREEN (4737 -3338);
DISPLAY INVISIBLE (4737 -3338);
FORCEPROP 2 LAST CDS_XR_PAGE_TITLE CR-303 : @S9S_MB_2U_LIB.S9S_MB_2U(SCH_1):PAGE303
J 0
(-3165 1925);
DISPLAY 0.638298 (-3165 1925);
PAINT PINK (-3165 1925);
DISPLAY INVISIBLE (-3165 1925);
WIRE 16 -1 (-3600 1375)(-3600 1225);
WIRE 16 -1 (-3600 2150)(-3600 2050);
WIRE 16 -1 (-3575 -1400)(-3575 -1550);
WIRE 16 -1 (1000 -2025)(1000 -2100);
WIRE 16 -1 (1000 750)(1000 675);
WIRE 16 -1 (-3575 -625)(-3575 -725);
WIRE 16 -1 (-3575 -1200)(-3575 -1025);
WIRE 16 -1 (-3575 -1025)(-450 -1025);
FORCEPROP 2 LAST SIG_NAME HSC_VDD_R_4
J 0
(-985 -1015);
DISPLAY 0.808511 (-985 -1015);
WIRE 16 -1 (-3575 -925)(-3575 -1025);
WIRE 16 -1 (-450 -1425)(-2700 -1425);
FORCEPROP 2 LAST SIG_NAME HSC_ON
J 0
(-985 -1415);
DISPLAY 0.808511 (-985 -1415);
WIRE 16 -1 (-2700 -1425)(-2850 -1425);
WIRE 16 -1 (-2700 -1425)(-2700 -1850);
WIRE 16 -1 (-2025 -1525)(-1975 -1525);
WIRE 16 -1 (-450 -1525)(-1975 -1525);
FORCEPROP 2 LAST SIG_NAME HSC_OCREF
J 0
(-985 -1515);
DISPLAY 0.808511 (-985 -1515);
WIRE 16 -1 (-1975 -1850)(-1975 -1525);
WIRE 16 -1 (-1400 -1300)(-1975 -1300);
FORCEPROP 2 LAST SIG_NAME HSC_SCREF
J 0
(-1985 -1290);
DISPLAY 0.808511 (-1985 -1290);
WIRE 16 -1 (-450 -1625)(-1475 -1625);
FORCEPROP 2 LAST SIG_NAME HSC_CS_4
J 0
(-985 -1615);
DISPLAY 0.808511 (-985 -1615);
WIRE 16 -1 (-1475 -1625)(-1475 -1850);
WIRE 16 -1 (-1800 -1125)(-450 -1125);
FORCEPROP 2 LAST SIG_NAME HSC_MODE_4
J 0
(-985 -1115);
DISPLAY 0.808511 (-985 -1115);
WIRE 16 -1 (-1000 -1725)(-950 -1725);
WIRE 16 -1 (-450 -1725)(-950 -1725);
FORCEPROP 2 LAST SIG_NAME HSC_IMON
J 0
(-985 -1715);
DISPLAY 0.808511 (-985 -1715);
WIRE 16 -1 (-950 -1850)(-950 -1725);
WIRE 16 -1 (-875 -1225)(-875 -1300);
WIRE 16 -1 (-450 -1225)(-875 -1225);
FORCEPROP 2 LAST SIG_NAME HSC_SCREF_4
J 0
(-985 -1215);
DISPLAY 0.808511 (-985 -1215);
WIRE 16 -1 (-875 -1300)(-1200 -1300);
WIRE 16 -1 (-3600 1575)(-3600 1750);
WIRE 16 -1 (-3600 1750)(-450 1750);
FORCEPROP 2 LAST SIG_NAME HSC_VDD_R_3
J 0
(-1010 1760);
DISPLAY 0.808511 (-1010 1760);
WIRE 16 -1 (-3600 1850)(-3600 1750);
WIRE 16 -1 (-1425 1475)(-1975 1475);
FORCEPROP 2 LAST SIG_NAME HSC_SCREF
J 0
(-1985 1485);
DISPLAY 0.808511 (-1985 1485);
WIRE 16 -1 (-1800 1650)(-450 1650);
FORCEPROP 2 LAST SIG_NAME HSC_MODE_3
J 0
(-1010 1660);
DISPLAY 0.808511 (-1010 1660);
WIRE 16 -1 (-875 1550)(-875 1475);
WIRE 16 -1 (-450 1550)(-875 1550);
FORCEPROP 2 LAST SIG_NAME HSC_SCREF_3
J 0
(-1010 1560);
DISPLAY 0.808511 (-1010 1560);
WIRE 16 -1 (-875 1475)(-1225 1475);
WIRE 16 -1 (500 -1775)(1000 -1775);
FORCEPROP 2 LAST SIG_NAME HSC_SS
J 0
(640 -1765);
DISPLAY 0.808511 (640 -1765);
WIRE 16 -1 (1000 -1775)(2225 -1775);
WIRE 16 -1 (1000 -1775)(1000 -1825);
WIRE 16 -1 (500 -1475)(975 -1475);
FORCEPROP 2 LAST SIG_NAME HSC_NC1_4
J 0
(640 -1465);
DISPLAY 0.808511 (640 -1465);
WIRE 16 -1 (575 -1275)(575 -1200);
FORCEPROP 2 LAST SIG_NAME HSC_D_OC_4
J 0
(640 -1190);
DISPLAY 0.808511 (640 -1190);
WIRE 16 -1 (575 -1275)(500 -1275);
WIRE 16 -1 (575 -1200)(1400 -1200);
WIRE 16 -1 (500 -1375)(1400 -1375);
FORCEPROP 2 LAST SIG_NAME HSC_FLT_TYPE_4
J 0
(640 -1365);
DISPLAY 0.808511 (640 -1365);
WIRE 16 -1 (1600 -1200)(2225 -1200);
FORCEPROP 2 LAST SIG_NAME HSC_D_OC_R
J 0
(1765 -1190);
DISPLAY 0.808511 (1765 -1190);
WIRE 16 -1 (1600 -1375)(2225 -1375);
FORCEPROP 2 LAST SIG_NAME HSC_FLT_TYPE
J 0
(1715 -1365);
DISPLAY 0.808511 (1715 -1365);
WIRE 16 -1 (500 -1675)(2225 -1675);
FORCEPROP 2 LAST SIG_NAME HSC_VTEMP
J 0
(640 -1665);
DISPLAY 0.808511 (640 -1665);
WIRE 16 -1 (500 -1575)(2225 -1575);
FORCEPROP 2 LAST SIG_NAME HSC_FAULT
J 0
(640 -1565);
DISPLAY 0.808511 (640 -1565);
WIRE 16 -1 (500 1000)(1000 1000);
FORCEPROP 2 LAST SIG_NAME HSC_SS
J 0
(615 1010);
DISPLAY 0.808511 (615 1010);
WIRE 16 -1 (1000 1000)(2250 1000);
WIRE 16 -1 (1000 1000)(1000 950);
WIRE 16 -1 (500 1300)(950 1300);
FORCEPROP 2 LAST SIG_NAME HSC_NC1_3
J 0
(615 1310);
DISPLAY 0.808511 (615 1310);
WIRE 16 -1 (625 1500)(625 1575);
FORCEPROP 2 LAST SIG_NAME HSC_D_OC_3
J 0
(615 1585);
DISPLAY 0.808511 (615 1585);
WIRE 16 -1 (625 1500)(500 1500);
WIRE 16 -1 (625 1575)(1400 1575);
WIRE 16 -1 (500 1400)(1400 1400);
FORCEPROP 2 LAST SIG_NAME HSC_FLT_TYPE_3
J 0
(615 1410);
DISPLAY 0.808511 (615 1410);
WIRE 16 -1 (1600 1575)(2250 1575);
FORCEPROP 2 LAST SIG_NAME HSC_D_OC_R
J 0
(1815 1585);
DISPLAY 0.808511 (1815 1585);
WIRE 16 -1 (1600 1400)(2250 1400);
FORCEPROP 2 LAST SIG_NAME HSC_FLT_TYPE
J 0
(1740 1410);
DISPLAY 0.808511 (1740 1410);
WIRE 16 -1 (500 1100)(2250 1100);
FORCEPROP 2 LAST SIG_NAME HSC_VTEMP
J 0
(615 1110);
DISPLAY 0.808511 (615 1110);
WIRE 16 -1 (500 1200)(2250 1200);
FORCEPROP 2 LAST SIG_NAME HSC_FAULT
J 0
(615 1210);
DISPLAY 0.808511 (615 1210);
WIRE 16 -1 (-1000 1050)(-950 1050);
WIRE 16 -1 (-450 1050)(-950 1050);
FORCEPROP 2 LAST SIG_NAME HSC_IMON
J 0
(-1010 1060);
DISPLAY 0.808511 (-1010 1060);
WIRE 16 -1 (-950 925)(-950 1050);
WIRE 16 -1 (-450 1150)(-1475 1150);
FORCEPROP 2 LAST SIG_NAME HSC_CS_3
J 0
(-1010 1160);
DISPLAY 0.808511 (-1010 1160);
WIRE 16 -1 (-1475 1150)(-1475 925);
WIRE 16 -1 (-1950 925)(-1950 1250);
WIRE 16 -1 (-1950 1250)(-450 1250);
FORCEPROP 2 LAST SIG_NAME HSC_OCREF
J 0
(-1010 1260);
DISPLAY 0.808511 (-1010 1260);
WIRE 16 -1 (-2000 1250)(-1950 1250);
WIRE 16 -1 (-450 1350)(-2700 1350);
FORCEPROP 2 LAST SIG_NAME HSC_ON
J 0
(-1010 1360);
DISPLAY 0.808511 (-1010 1360);
WIRE 16 -1 (-2825 1350)(-2700 1350);
WIRE 16 -1 (-2700 1350)(-2700 925);
WIRE 16 -1 (1125 2400)(1125 2375);
WIRE 16 -1 (1125 2375)(625 2375);
WIRE 16 -1 (625 2375)(625 2300);
WIRE 16 -1 (500 2300)(625 2300);
WIRE 16 -1 (625 2300)(625 2250);
WIRE 16 -1 (500 2250)(625 2250);
WIRE 16 -1 (625 2250)(625 2200);
WIRE 16 -1 (500 2200)(625 2200);
WIRE 16 -1 (625 2200)(625 2150);
WIRE 16 -1 (625 2150)(625 2100);
WIRE 16 -1 (500 2150)(625 2150);
WIRE 16 -1 (625 2100)(625 2050);
WIRE 16 -1 (500 2100)(625 2100);
WIRE 16 -1 (625 2050)(625 2000);
WIRE 16 -1 (500 2050)(625 2050);
WIRE 16 -1 (625 2000)(625 1950);
WIRE 16 -1 (500 2000)(625 2000);
WIRE 16 -1 (625 1950)(625 1900);
WIRE 16 -1 (500 1950)(625 1950);
WIRE 16 -1 (625 1900)(625 1850);
WIRE 16 -1 (500 1900)(625 1900);
WIRE 16 -1 (625 1850)(500 1850);
WIRE 16 -1 (1125 -375)(1125 -400);
WIRE 16 -1 (1125 -400)(625 -400);
WIRE 16 -1 (625 -400)(625 -475);
WIRE 16 -1 (500 -475)(625 -475);
WIRE 16 -1 (625 -475)(625 -525);
WIRE 16 -1 (500 -525)(625 -525);
WIRE 16 -1 (625 -525)(625 -575);
WIRE 16 -1 (500 -575)(625 -575);
WIRE 16 -1 (625 -575)(625 -625);
WIRE 16 -1 (625 -625)(625 -675);
WIRE 16 -1 (500 -625)(625 -625);
WIRE 16 -1 (625 -675)(625 -725);
WIRE 16 -1 (500 -675)(625 -675);
WIRE 16 -1 (625 -725)(625 -775);
WIRE 16 -1 (500 -725)(625 -725);
WIRE 16 -1 (625 -775)(625 -825);
WIRE 16 -1 (500 -775)(625 -775);
WIRE 16 -1 (625 -825)(625 -875);
WIRE 16 -1 (500 -825)(625 -825);
WIRE 16 -1 (625 -875)(625 -925);
WIRE 16 -1 (500 -875)(625 -875);
WIRE 16 -1 (625 -925)(500 -925);
WIRE 16 -1 (-950 2400)(-950 2350);
WIRE 16 -1 (-950 2350)(-650 2350);
WIRE 16 -1 (-650 2350)(-650 2300);
WIRE 16 -1 (-450 2300)(-650 2300);
WIRE 16 -1 (-650 2300)(-650 2250);
WIRE 16 -1 (-450 2250)(-650 2250);
WIRE 16 -1 (-650 2250)(-650 2200);
WIRE 16 -1 (-450 2200)(-650 2200);
WIRE 16 -1 (-650 2200)(-650 2150);
WIRE 16 -1 (-450 2150)(-650 2150);
WIRE 16 -1 (-650 2150)(-650 2100);
WIRE 16 -1 (-450 2100)(-650 2100);
WIRE 16 -1 (-650 2100)(-650 2050);
WIRE 16 -1 (-450 2050)(-650 2050);
WIRE 16 -1 (-650 2050)(-650 2000);
WIRE 16 -1 (-450 2000)(-650 2000);
WIRE 16 -1 (-650 2000)(-650 1950);
WIRE 16 -1 (-450 1950)(-650 1950);
WIRE 16 -1 (-650 1950)(-650 1900);
WIRE 16 -1 (-650 1900)(-450 1900);
WIRE 16 -1 (-2725 1625)(-2725 1650);
WIRE 16 -1 (-2725 1650)(-2000 1650);
WIRE 16 -1 (-2700 575)(-2700 650);
WIRE 16 -1 (-1950 650)(-2700 650);
WIRE 16 -1 (-2700 725)(-2700 650);
WIRE 16 -1 (-1950 650)(-1475 650);
WIRE 16 -1 (-1950 725)(-1950 650);
WIRE 16 -1 (-950 650)(-1475 650);
WIRE 16 -1 (-1475 725)(-1475 650);
WIRE 16 -1 (-950 650)(-500 650);
WIRE 16 -1 (-950 725)(-950 650);
WIRE 16 -1 (-500 850)(-500 650);
WIRE 16 -1 (-450 850)(-500 850);
WIRE 16 -1 (-950 -375)(-950 -425);
WIRE 16 -1 (-950 -425)(-650 -425);
WIRE 16 -1 (-650 -425)(-650 -475);
WIRE 16 -1 (-450 -475)(-650 -475);
WIRE 16 -1 (-650 -475)(-650 -525);
WIRE 16 -1 (-450 -525)(-650 -525);
WIRE 16 -1 (-650 -525)(-650 -575);
WIRE 16 -1 (-450 -575)(-650 -575);
WIRE 16 -1 (-650 -575)(-650 -625);
WIRE 16 -1 (-450 -625)(-650 -625);
WIRE 16 -1 (-650 -625)(-650 -675);
WIRE 16 -1 (-450 -675)(-650 -675);
WIRE 16 -1 (-650 -675)(-650 -725);
WIRE 16 -1 (-450 -725)(-650 -725);
WIRE 16 -1 (-650 -725)(-650 -775);
WIRE 16 -1 (-450 -775)(-650 -775);
WIRE 16 -1 (-650 -775)(-650 -825);
WIRE 16 -1 (-450 -825)(-650 -825);
WIRE 16 -1 (-650 -825)(-650 -875);
WIRE 16 -1 (-650 -875)(-450 -875);
WIRE 16 -1 (-2700 -1175)(-2700 -1125);
WIRE 16 -1 (-2700 -1125)(-2000 -1125);
WIRE 16 -1 (-2700 -2200)(-2700 -2125);
WIRE 16 -1 (-1975 -2125)(-2700 -2125);
WIRE 16 -1 (-2700 -2050)(-2700 -2125);
WIRE 16 -1 (-1975 -2125)(-1475 -2125);
WIRE 16 -1 (-1975 -2050)(-1975 -2125);
WIRE 16 -1 (-950 -2125)(-1475 -2125);
WIRE 16 -1 (-1475 -2050)(-1475 -2125);
WIRE 16 -1 (-950 -2050)(-950 -2125);
WIRE 16 -1 (-950 -2125)(-500 -2125);
WIRE 16 -1 (-500 -1925)(-500 -2125);
WIRE 16 -1 (-450 -1925)(-500 -1925);
DOT 1 (-2700 -2125);
DOT 1 (-3575 -1025);
DOT 1 (-2700 -1425);
DOT 1 (-1975 -2125);
DOT 1 (-1475 -2125);
DOT 1 (-950 -2125);
DOT 1 (-1975 -1525);
DOT 1 (-950 -1725);
DOT 1 (-650 -825);
DOT 1 (-650 -775);
DOT 1 (-650 -675);
DOT 1 (-650 -725);
DOT 1 (-650 -625);
DOT 1 (-650 -575);
DOT 1 (-650 -525);
DOT 1 (-650 -475);
DOT 1 (-3600 1750);
DOT 1 (-2700 650);
DOT 1 (-2700 1350);
DOT 1 (-1950 650);
DOT 1 (-1475 650);
DOT 1 (-1950 1250);
DOT 1 (-950 650);
DOT 1 (-950 1050);
DOT 1 (-650 1950);
DOT 1 (-650 2000);
DOT 1 (-650 2050);
DOT 1 (-650 2100);
DOT 1 (-650 2150);
DOT 1 (-650 2200);
DOT 1 (-650 2250);
DOT 1 (-650 2300);
DOT 1 (1000 -1775);
DOT 1 (625 -875);
DOT 1 (625 -775);
DOT 1 (625 -825);
DOT 1 (625 -675);
DOT 1 (625 -725);
DOT 1 (625 -625);
DOT 1 (625 -575);
DOT 1 (625 -525);
DOT 1 (625 -475);
DOT 1 (1000 1000);
DOT 1 (625 1900);
DOT 1 (625 1950);
DOT 1 (625 2000);
DOT 1 (625 2050);
DOT 1 (625 2100);
DOT 1 (625 2150);
DOT 1 (625 2200);
DOT 1 (625 2300);
DOT 1 (625 2250);
FORCENOTE
LATCH OFF MODE
(-4475 2700) 0;
DISPLAY LEFT (-4475 2700);
DISPLAY 1.021277 (-4475 2700);
FORCENOTE
HOT SWAT CIRCUIT
(-4496 3138) 0;
DISPLAY LEFT (-4496 3138);
DISPLAY 2.000000 (-4496 3138);
FORCENOTE
ADDRESS 0X20
(-4475 2766) 0;
DISPLAY LEFT (-4475 2766);
DISPLAY 1.021277 (-4475 2766);
FORCENOTE
OCP=240A
(-4500 3034) 0;
DISPLAY LEFT (-4500 3034);
DISPLAY 1.595745 (-4500 3034);
FORCENOTE
UV =10.091V
(-4475 2825) 0;
DISPLAY LEFT (-4475 2825);
DISPLAY 1.021277 (-4475 2825);
FORCENOTE
OV =14.333V
(-4475 2875) 0;
DISPLAY LEFT (-4475 2875);
DISPLAY 1.021277 (-4475 2875);
FORCENOTE
OCW=220A
(-4500 2959) 0;
DISPLAY LEFT (-4500 2959);
DISPLAY 1.595745 (-4500 2959);
FORCENOTE
FPH=220A
(-3775 2959) 0;
DISPLAY LEFT (-3775 2959);
DISPLAY 1.595745 (-3775 2959);
FORCENOTE
FOR MP5981:
(-425 415) 0;
DISPLAY LEFT (-425 415);
DISPLAY 1.021277 (-425 415);
FORCENOTE
DNI PR3992, PR3993, PR3988
(-425 350) 0;
DISPLAY LEFT (-425 350);
DISPLAY 1.021277 (-425 350);
FORCENOTE
CHANGE PU296 TO AL005981A00
(-425 285) 0;
DISPLAY LEFT (-425 285);
DISPLAY 1.021277 (-425 285);
FORCENOTE
20211116 MODIFY FOR GT
(-1325 3075) 0;
DISPLAY LEFT (-1325 3075);
DISPLAY 2.510638 (-1325 3075);
PAINT PINK (-1325 3075);
FORCENOTE
CHANGE PU297 TO AL005981A00
(-450 -2540) 0;
DISPLAY LEFT (-450 -2540);
DISPLAY 1.021277 (-450 -2540);
FORCENOTE
DNI PR3994, PR3995, PR3989
(-450 -2475) 0;
DISPLAY LEFT (-450 -2475);
DISPLAY 1.021277 (-450 -2475);
FORCENOTE
FOR MP5981:
(-450 -2410) 0;
DISPLAY LEFT (-450 -2410);
DISPLAY 1.021277 (-450 -2410);
FORCENOTE
VOUT SLEW RATE: 2V/MS
(1500 -2050) 0;
DISPLAY LEFT (1500 -2050);
DISPLAY 1.021277 (1500 -2050);
FORCENOTE
SOFT START TIME=6MS.
(1500 -1985) 0;
DISPLAY LEFT (1500 -1985);
DISPLAY 1.021277 (1500 -1985);
FORCENOTE
SOFT START TIME=6MS.
(1500 791) 0;
DISPLAY LEFT (1500 791);
DISPLAY 1.021277 (1500 791);
FORCENOTE
VOUT SLEW RATE: 2V/MS
(1500 725) 0;
DISPLAY LEFT (1500 725);
DISPLAY 1.021277 (1500 725);
QUIT
